FILE_TYPE = MACRO_DRAWING;
SET COLOR_WIRE YELLOW;
SET COLOR_PROP MONO;
SET COLOR_DOT WHITE;
SET COLOR_ARC YELLOW;
SET COLOR_BODY GREEN;
SET COLOR_NOTE MONO;
SET PROP_DISPLAY VALUE;
SET PAGE_NUMBER P84;
FORCEADD GND..1
R 2
(-3500 1475);
FORCEPROP 3 LASTPIN (-3500 1525) SIG_NAME GND\g
J 0
(-3490 1535);
DISPLAY 0.659574 (-3490 1535);
PAINT MONO (-3490 1535);
DISPLAY INVISIBLE (-3490 1535);
FORCEPROP 1 LAST VOLTAGE 0
J 0
(-3500 1475);
PAINT SKYBLUE (-3500 1475);
DISPLAY INVISIBLE (-3500 1475);
FORCEPROP 1 LAST SIZE 1B
J 2
(-3575 1425);
DISPLAY 1.170213 (-3575 1425);
PAINT GREEN (-3575 1425);
DISPLAY INVISIBLE (-3575 1425);
FORCEPROP 2 LAST CDS_LIB mstr_symbols
J 0
(-3500 1475);
DISPLAY 0.787234 (-3500 1475);
PAINT MONO (-3500 1475);
DISPLAY INVISIBLE (-3500 1475);
FORCEPROP 2 LAST BOM_COST MEM
J 0
(-3500 1480);
PAINT ORANGE (-3500 1480);
DISPLAY INVISIBLE (-3500 1480);
FORCEPROP 1 LAST BODY_TYPE PLUMBING
J 2
(-3455 1432);
DISPLAY 0.340426 (-3455 1432);
PAINT GREEN (-3455 1432);
DISPLAY INVISIBLE (-3455 1432);
FORCEPROP 1 LAST PATH I1
J 2
(-3575 1475);
DISPLAY 0.872340 (-3575 1475);
PAINT AQUA (-3575 1475);
DISPLAY INVISIBLE (-3575 1475);
FORCEPROP 2 LAST ROOM DDR4_CH_C
J 0
(-3500 1480);
PAINT ORANGE (-3500 1480);
DISPLAY INVISIBLE (-3500 1480);
FORCEPROP 1 LAST HDL_POWER GND
J 2
(-3500 1625);
DISPLAY 0.553191 (-3500 1625);
PAINT GREEN (-3500 1625);
DISPLAY INVISIBLE (-3500 1625);
FORCEADD OFFPAGE..1
(-2650 3325);
FORCEPROP 2 LAST $XR1 83 
J 0
(-2991 3325);
DISPLAY 0.638298 (-2991 3325);
PAINT MONO (-2991 3325);
FORCEPROP 2 LAST $XR0 60 
J 0
(-2901 3325);
DISPLAY 0.638298 (-2901 3325);
PAINT MONO (-2901 3325);
FORCEPROP 2 LAST CDS_LIB mstr_standard
J 0
(-2650 3325);
DISPLAY 0.787234 (-2650 3325);
PAINT MONO (-2650 3325);
DISPLAY INVISIBLE (-2650 3325);
FORCEPROP 1 LAST OFFPAGE TRUE
J 0
(-2325 3200);
DISPLAY 0.936170 (-2325 3200);
PAINT GREEN (-2325 3200);
DISPLAY INVISIBLE (-2325 3200);
FORCEPROP 1 LAST COMMENT_BODY TRUE
J 0
(-2525 3225);
DISPLAY 0.936170 (-2525 3225);
PAINT GREEN (-2525 3225);
DISPLAY INVISIBLE (-2525 3225);
FORCEPROP 2 LAST PATH I10
J 0
(-2900 3375);
DISPLAY 1.021277 (-2900 3375);
PAINT ORANGE (-2900 3375);
DISPLAY INVISIBLE (-2900 3375);
FORCEADD PVTT_KLM..1
(600 2425);
FORCEPROP 3 LASTPIN (600 2375) SIG_NAME PVTT_KLM\g
J 0
(610 2385);
DISPLAY 0.659574 (610 2385);
PAINT MONO (610 2385);
DISPLAY INVISIBLE (610 2385);
FORCEPROP 1 LAST VOLTAGE 0.6V
J 0
(555 2382);
DISPLAY 0.340426 (555 2382);
PAINT SKYBLUE (555 2382);
DISPLAY INVISIBLE (555 2382);
FORCEPROP 2 LAST BOM_COST MEM
J 0
(600 2430);
PAINT ORANGE (600 2430);
DISPLAY INVISIBLE (600 2430);
FORCEPROP 2 LAST CDS_LIB mstr_symbols
J 0
(600 2425);
PAINT ORANGE (600 2425);
DISPLAY INVISIBLE (600 2425);
FORCEPROP 1 LAST BODY_TYPE PLUMBING
J 0
(555 2382);
DISPLAY 0.340426 (555 2382);
PAINT GREEN (555 2382);
DISPLAY INVISIBLE (555 2382);
FORCEPROP 1 LAST PATH I100
J 0
(650 2450);
DISPLAY 0.872340 (650 2450);
PAINT AQUA (650 2450);
DISPLAY INVISIBLE (650 2450);
FORCEPROP 2 LAST ROOM DDR4_CH_C
J 0
(600 2525);
DISPLAY 0.787234 (600 2525);
PAINT ORANGE (600 2525);
DISPLAY INVISIBLE (600 2525);
FORCEPROP 1 LAST HDL_POWER PVTT_KLM
J 1
(600 2475);
DISPLAY 0.872340 (600 2475);
PAINT GREEN (600 2475);
DISPLAY INVISIBLE (600 2475);
FORCEADD PVPP_KLM..1
(750 2725);
FORCEPROP 3 LASTPIN (750 2675) SIG_NAME PVPP_KLM\g
J 0
(760 2685);
DISPLAY 0.659574 (760 2685);
PAINT MONO (760 2685);
DISPLAY INVISIBLE (760 2685);
FORCEPROP 1 LAST VOLTAGE 2.5V
J 0
(705 2682);
DISPLAY 0.340426 (705 2682);
PAINT SKYBLUE (705 2682);
DISPLAY INVISIBLE (705 2682);
FORCEPROP 0 LAST BOM_COST MEM
J 0
(750 2825);
PAINT ORANGE (750 2825);
DISPLAY INVISIBLE (750 2825);
FORCEPROP 2 LAST CDS_LIB mstr_symbols
J 0
(750 2725);
PAINT ORANGE (750 2725);
DISPLAY INVISIBLE (750 2725);
FORCEPROP 1 LAST BODY_TYPE PLUMBING
J 0
(705 2682);
DISPLAY 0.340426 (705 2682);
PAINT GREEN (705 2682);
DISPLAY INVISIBLE (705 2682);
FORCEPROP 1 LAST PATH I101
J 0
(800 2750);
DISPLAY 0.872340 (800 2750);
PAINT AQUA (800 2750);
DISPLAY INVISIBLE (800 2750);
FORCEPROP 2 LAST ROOM DDR4_CH_C
J 0
(750 2825);
PAINT ORANGE (750 2825);
DISPLAY INVISIBLE (750 2825);
FORCEPROP 1 LAST HDL_POWER PVPP_KLM
J 1
(750 2775);
DISPLAY 0.872340 (750 2775);
PAINT GREEN (750 2775);
DISPLAY INVISIBLE (750 2775);
FORCEADD SCONN288_H44441003..2
(1600 3975);
FORCEPROP 1 LAST PART_NUMBER H44441-003
J 0
(1200 2875);
DISPLAY 0.617021 (1200 2875);
PAINT BLUE (1200 2875);
FORCEPROP 2 LASTPIN (2050 4825) $PN 51
J 0
(2060 4835);
DISPLAY 0.617021 (2060 4835);
PAINT ORANGE (2060 4835);
FORCEPROP 2 LASTPIN (2050 4775) $PN 52
J 0
(2060 4785);
DISPLAY 0.617021 (2060 4785);
PAINT ORANGE (2060 4785);
FORCEPROP 2 LASTPIN (2050 4725) $PN 132
J 0
(2060 4735);
DISPLAY 0.617021 (2060 4735);
PAINT ORANGE (2060 4735);
FORCEPROP 2 LASTPIN (2050 4675) $PN 133
J 0
(2060 4685);
DISPLAY 0.617021 (2060 4685);
PAINT ORANGE (2060 4685);
FORCEPROP 2 LASTPIN (2050 4625) $PN 121
J 0
(2060 4635);
DISPLAY 0.617021 (2060 4635);
PAINT ORANGE (2060 4635);
FORCEPROP 2 LASTPIN (2050 4575) $PN 122
J 0
(2060 4585);
DISPLAY 0.617021 (2060 4585);
PAINT ORANGE (2060 4585);
FORCEPROP 2 LASTPIN (2050 4525) $PN 110
J 0
(2060 4535);
DISPLAY 0.617021 (2060 4535);
PAINT ORANGE (2060 4535);
FORCEPROP 2 LASTPIN (2050 4475) $PN 111
J 0
(2060 4485);
DISPLAY 0.617021 (2060 4485);
PAINT ORANGE (2060 4485);
FORCEPROP 2 LASTPIN (2050 4425) $PN 99
J 0
(2060 4435);
DISPLAY 0.617021 (2060 4435);
PAINT ORANGE (2060 4435);
FORCEPROP 2 LASTPIN (2050 4375) $PN 100
J 0
(2060 4385);
DISPLAY 0.617021 (2060 4385);
PAINT ORANGE (2060 4385);
FORCEPROP 2 LASTPIN (2050 4325) $PN 40
J 0
(2060 4335);
DISPLAY 0.617021 (2060 4335);
PAINT ORANGE (2060 4335);
FORCEPROP 2 LASTPIN (2050 4275) $PN 41
J 0
(2060 4285);
DISPLAY 0.617021 (2060 4285);
PAINT ORANGE (2060 4285);
FORCEPROP 2 LASTPIN (2050 4225) $PN 29
J 0
(2060 4235);
DISPLAY 0.617021 (2060 4235);
PAINT ORANGE (2060 4235);
FORCEPROP 2 LASTPIN (2050 4175) $PN 30
J 0
(2060 4185);
DISPLAY 0.617021 (2060 4185);
PAINT ORANGE (2060 4185);
FORCEPROP 2 LASTPIN (2050 4125) $PN 18
J 0
(2060 4135);
DISPLAY 0.617021 (2060 4135);
PAINT ORANGE (2060 4135);
FORCEPROP 2 LASTPIN (2050 4075) $PN 19
J 0
(2060 4085);
DISPLAY 0.617021 (2060 4085);
PAINT ORANGE (2060 4085);
FORCEPROP 2 LASTPIN (2050 4025) $PN 7
J 0
(2060 4035);
DISPLAY 0.617021 (2060 4035);
PAINT ORANGE (2060 4035);
FORCEPROP 2 LASTPIN (2050 3975) $PN 8
J 0
(2060 3985);
DISPLAY 0.617021 (2060 3985);
PAINT ORANGE (2060 3985);
FORCEPROP 2 LASTPIN (2050 3875) $PN 196
J 0
(2060 3885);
DISPLAY 0.617021 (2060 3885);
PAINT ORANGE (2060 3885);
FORCEPROP 2 LASTPIN (2050 3625) $PN 256
J 0
(2060 3635);
DISPLAY 0.617021 (2060 3635);
PAINT ORANGE (2060 3635);
FORCEPROP 2 LASTPIN (2050 3575) $PN 255
J 0
(2060 3585);
DISPLAY 0.617021 (2060 3585);
PAINT ORANGE (2060 3585);
FORCEPROP 2 LASTPIN (2050 3525) $PN 245
J 0
(2060 3535);
DISPLAY 0.617021 (2060 3535);
PAINT ORANGE (2060 3535);
FORCEPROP 2 LASTPIN (2050 3475) $PN 244
J 0
(2060 3485);
DISPLAY 0.617021 (2060 3485);
PAINT ORANGE (2060 3485);
FORCEPROP 2 LASTPIN (2050 3375) $PN 185
J 0
(2060 3385);
DISPLAY 0.617021 (2060 3385);
PAINT ORANGE (2060 3385);
FORCEPROP 2 LASTPIN (2050 3325) $PN 175
J 0
(2060 3335);
DISPLAY 0.617021 (2060 3335);
PAINT ORANGE (2060 3335);
FORCEPROP 2 LASTPIN (2050 3275) $PN 174
J 0
(2060 3285);
DISPLAY 0.617021 (2060 3285);
PAINT ORANGE (2060 3285);
FORCEPROP 2 LASTPIN (2050 3225) $PN 164
J 0
(2060 3235);
DISPLAY 0.617021 (2060 3235);
PAINT ORANGE (2060 3235);
FORCEPROP 2 LASTPIN (2050 3175) $PN 163
J 0
(2060 3185);
DISPLAY 0.617021 (2060 3185);
PAINT ORANGE (2060 3185);
FORCEPROP 2 LASTPIN (2050 3075) $PN 152
J 0
(2060 3085);
DISPLAY 0.617021 (2060 3085);
PAINT ORANGE (2060 3085);
FORCEPROP 2 LASTPIN (2050 3125) $PN 153
J 0
(2060 3135);
DISPLAY 0.617021 (2060 3135);
PAINT ORANGE (2060 3135);
FORCEPROP 2 LASTPIN (2050 3425) $PN 186
J 0
(2060 3435);
DISPLAY 0.617021 (2060 3435);
PAINT ORANGE (2060 3435);
FORCEPROP 2 LASTPIN (2050 3925) $PN 197
J 0
(2060 3935);
DISPLAY 0.617021 (2060 3935);
PAINT ORANGE (2060 3935);
FORCEPROP 2 LASTPIN (2050 3675) $PN 266
J 0
(2060 3685);
DISPLAY 0.617021 (2060 3685);
PAINT ORANGE (2060 3685);
FORCEPROP 2 LASTPIN (2050 3725) $PN 267
J 0
(2060 3735);
DISPLAY 0.617021 (2060 3735);
PAINT ORANGE (2060 3735);
FORCEPROP 2 LASTPIN (2050 3775) $PN 277
J 0
(2060 3785);
DISPLAY 0.617021 (2060 3785);
PAINT ORANGE (2060 3785);
FORCEPROP 2 LASTPIN (2050 3825) $PN 278
J 0
(2060 3835);
DISPLAY 0.617021 (2060 3835);
PAINT ORANGE (2060 3835);
FORCEPROP 1 LAST MATERIAL SCONN
J 0
(1200 5025);
DISPLAY 0.617021 (1200 5025);
PAINT SKYBLUE (1200 5025);
FORCEPROP 1 LAST LOCATION J9M1
J 0
(1200 5075);
DISPLAY 0.617021 (1200 5075);
PAINT AQUA (1200 5075);
FORCEPROP 0 LAST BOM_SS NOPOP
J 0
(1441 5026);
DISPLAY 1.021277 (1441 5026);
PAINT BROWN (1441 5026);
DISPLAY BOTH (1441 5026);
FORCEPROP 1 LAST PACK_TYPE PIP
J 0
(1200 5125);
PAINT SKYBLUE (1200 5125);
DISPLAY INVISIBLE (1200 5125);
FORCEPROP 2 LAST BOM_COST MEM
J 0
(1600 3975);
PAINT ORANGE (1600 3975);
DISPLAY INVISIBLE (1600 3975);
FORCEPROP 2 LAST CDS_LIB mstr_sconn
J 0
(1600 3975);
PAINT ORANGE (1600 3975);
DISPLAY INVISIBLE (1600 3975);
FORCEPROP 2 LAST SEC_TYPE PIP
J 0
(1200 5125);
DISPLAY 1.021277 (1200 5125);
PAINT ORANGE (1200 5125);
DISPLAY INVISIBLE (1200 5125);
FORCEPROP 2 LAST SEC 2
J 0
(1200 5125);
DISPLAY 0.680851 (1200 5125);
PAINT MONO (1200 5125);
DISPLAY INVISIBLE (1200 5125);
FORCEPROP 2 LAST CDS_LOCATION J9M1
J 0
(1200 5075);
DISPLAY 0.617021 (1200 5075);
PAINT AQUA (1200 5075);
DISPLAY INVISIBLE (1200 5075);
FORCEPROP 1 LAST PATH I102
J 0
(1600 5025);
PAINT GREEN (1600 5025);
DISPLAY INVISIBLE (1600 5025);
FORCEPROP 2 LAST ROOM DDR4_CH_K
J 0
(1200 5175);
PAINT ORANGE (1200 5175);
DISPLAY INVISIBLE (1200 5175);
FORCEADD OFFPAGE..1
(-2250 4525);
FORCEPROP 2 LAST $XR1 83 
J 0
(-2591 4525);
DISPLAY 0.638298 (-2591 4525);
PAINT MONO (-2591 4525);
FORCEPROP 2 LAST $XR0 60 
J 0
(-2501 4525);
DISPLAY 0.638298 (-2501 4525);
PAINT MONO (-2501 4525);
FORCEPROP 2 LAST CDS_LIB mstr_standard
J 0
(-2250 4525);
DISPLAY 0.787234 (-2250 4525);
PAINT MONO (-2250 4525);
DISPLAY INVISIBLE (-2250 4525);
FORCEPROP 1 LAST OFFPAGE TRUE
J 0
(-1925 4400);
DISPLAY 0.936170 (-1925 4400);
PAINT GREEN (-1925 4400);
DISPLAY INVISIBLE (-1925 4400);
FORCEPROP 1 LAST COMMENT_BODY TRUE
J 0
(-2125 4425);
DISPLAY 0.936170 (-2125 4425);
PAINT GREEN (-2125 4425);
DISPLAY INVISIBLE (-2125 4425);
FORCEPROP 2 LAST PATH I103
J 0
(-2500 4575);
DISPLAY 1.021277 (-2500 4575);
PAINT ORANGE (-2500 4575);
DISPLAY INVISIBLE (-2500 4575);
FORCEADD TAP..6
(-1600 3775);
FORCEPROP 3 LASTPIN (-1550 3775) SIG_NAME M_K_MA<3>
J 0
(-1540 3785);
DISPLAY 0.659574 (-1540 3785);
PAINT MONO (-1540 3785);
DISPLAY INVISIBLE (-1540 3785);
FORCEPROP 1 LASTPIN (-1550 3775) BN 3
J 0
(-1600 3785);
DISPLAY 0.617021 (-1600 3785);
PAINT PINK (-1600 3785);
FORCEPROP 2 LAST CDS_LIB mstr_standard
J 2
(-1600 3775);
DISPLAY 0.787234 (-1600 3775);
PAINT MONO (-1600 3775);
DISPLAY INVISIBLE (-1600 3775);
FORCEPROP 1 LAST BODY_TYPE PLUMBING
J 0
(-1600 3725);
DISPLAY 1.234043 (-1600 3725);
PAINT GREEN (-1600 3725);
DISPLAY INVISIBLE (-1600 3725);
FORCEPROP 1 LAST HDL_TAP TRUE
J 0
(-1275 3650);
DISPLAY 1.234043 (-1275 3650);
PAINT GREEN (-1275 3650);
DISPLAY INVISIBLE (-1275 3650);
FORCEPROP 1 LAST PATH I104
J 0
(-1602 3775);
DISPLAY 0.872340 (-1602 3775);
PAINT GREEN (-1602 3775);
DISPLAY INVISIBLE (-1602 3775);
FORCEADD TAP..6
(-1600 3725);
FORCEPROP 3 LASTPIN (-1550 3725) SIG_NAME M_K_MA<2>
J 0
(-1540 3735);
DISPLAY 0.659574 (-1540 3735);
PAINT MONO (-1540 3735);
DISPLAY INVISIBLE (-1540 3735);
FORCEPROP 1 LASTPIN (-1550 3725) BN 2
J 0
(-1600 3735);
DISPLAY 0.617021 (-1600 3735);
PAINT PINK (-1600 3735);
FORCEPROP 2 LAST CDS_LIB mstr_standard
J 2
(-1600 3725);
DISPLAY 0.787234 (-1600 3725);
PAINT MONO (-1600 3725);
DISPLAY INVISIBLE (-1600 3725);
FORCEPROP 1 LAST BODY_TYPE PLUMBING
J 0
(-1600 3675);
DISPLAY 1.234043 (-1600 3675);
PAINT GREEN (-1600 3675);
DISPLAY INVISIBLE (-1600 3675);
FORCEPROP 1 LAST HDL_TAP TRUE
J 0
(-1275 3600);
DISPLAY 1.234043 (-1275 3600);
PAINT GREEN (-1275 3600);
DISPLAY INVISIBLE (-1275 3600);
FORCEPROP 1 LAST PATH I105
J 0
(-1602 3725);
DISPLAY 0.872340 (-1602 3725);
PAINT GREEN (-1602 3725);
DISPLAY INVISIBLE (-1602 3725);
FORCEADD TAP..6
(-1600 3925);
FORCEPROP 3 LASTPIN (-1550 3925) SIG_NAME M_K_MA<6>
J 0
(-1540 3935);
DISPLAY 0.659574 (-1540 3935);
PAINT MONO (-1540 3935);
DISPLAY INVISIBLE (-1540 3935);
FORCEPROP 1 LASTPIN (-1550 3925) BN 6
J 0
(-1600 3935);
DISPLAY 0.617021 (-1600 3935);
PAINT PINK (-1600 3935);
FORCEPROP 2 LAST CDS_LIB mstr_standard
J 2
(-1600 3925);
DISPLAY 0.787234 (-1600 3925);
PAINT MONO (-1600 3925);
DISPLAY INVISIBLE (-1600 3925);
FORCEPROP 1 LAST BODY_TYPE PLUMBING
J 0
(-1600 3875);
DISPLAY 1.234043 (-1600 3875);
PAINT GREEN (-1600 3875);
DISPLAY INVISIBLE (-1600 3875);
FORCEPROP 1 LAST HDL_TAP TRUE
J 0
(-1275 3800);
DISPLAY 1.234043 (-1275 3800);
PAINT GREEN (-1275 3800);
DISPLAY INVISIBLE (-1275 3800);
FORCEPROP 1 LAST PATH I106
J 0
(-1602 3925);
DISPLAY 0.872340 (-1602 3925);
PAINT GREEN (-1602 3925);
DISPLAY INVISIBLE (-1602 3925);
FORCEADD TAP..6
(-1600 3875);
FORCEPROP 3 LASTPIN (-1550 3875) SIG_NAME M_K_MA<5>
J 0
(-1540 3885);
DISPLAY 0.659574 (-1540 3885);
PAINT MONO (-1540 3885);
DISPLAY INVISIBLE (-1540 3885);
FORCEPROP 1 LASTPIN (-1550 3875) BN 5
J 0
(-1600 3885);
DISPLAY 0.617021 (-1600 3885);
PAINT PINK (-1600 3885);
FORCEPROP 2 LAST CDS_LIB mstr_standard
J 2
(-1600 3875);
DISPLAY 0.787234 (-1600 3875);
PAINT MONO (-1600 3875);
DISPLAY INVISIBLE (-1600 3875);
FORCEPROP 1 LAST BODY_TYPE PLUMBING
J 0
(-1600 3825);
DISPLAY 1.234043 (-1600 3825);
PAINT GREEN (-1600 3825);
DISPLAY INVISIBLE (-1600 3825);
FORCEPROP 1 LAST HDL_TAP TRUE
J 0
(-1275 3750);
DISPLAY 1.234043 (-1275 3750);
PAINT GREEN (-1275 3750);
DISPLAY INVISIBLE (-1275 3750);
FORCEPROP 1 LAST PATH I107
J 0
(-1602 3875);
DISPLAY 0.872340 (-1602 3875);
PAINT GREEN (-1602 3875);
DISPLAY INVISIBLE (-1602 3875);
FORCEADD TAP..6
(-1600 3825);
FORCEPROP 3 LASTPIN (-1550 3825) SIG_NAME M_K_MA<4>
J 0
(-1540 3835);
DISPLAY 0.659574 (-1540 3835);
PAINT MONO (-1540 3835);
DISPLAY INVISIBLE (-1540 3835);
FORCEPROP 1 LASTPIN (-1550 3825) BN 4
J 0
(-1600 3835);
DISPLAY 0.617021 (-1600 3835);
PAINT PINK (-1600 3835);
FORCEPROP 2 LAST CDS_LIB mstr_standard
J 2
(-1600 3825);
DISPLAY 0.787234 (-1600 3825);
PAINT MONO (-1600 3825);
DISPLAY INVISIBLE (-1600 3825);
FORCEPROP 1 LAST BODY_TYPE PLUMBING
J 0
(-1600 3775);
DISPLAY 1.234043 (-1600 3775);
PAINT GREEN (-1600 3775);
DISPLAY INVISIBLE (-1600 3775);
FORCEPROP 1 LAST HDL_TAP TRUE
J 0
(-1275 3700);
DISPLAY 1.234043 (-1275 3700);
PAINT GREEN (-1275 3700);
DISPLAY INVISIBLE (-1275 3700);
FORCEPROP 1 LAST PATH I108
J 0
(-1602 3825);
DISPLAY 0.872340 (-1602 3825);
PAINT GREEN (-1602 3825);
DISPLAY INVISIBLE (-1602 3825);
FORCEADD TAP..6
(-1600 3975);
FORCEPROP 3 LASTPIN (-1550 3975) SIG_NAME M_K_MA<7>
J 0
(-1540 3985);
DISPLAY 0.659574 (-1540 3985);
PAINT MONO (-1540 3985);
DISPLAY INVISIBLE (-1540 3985);
FORCEPROP 1 LASTPIN (-1550 3975) BN 7
J 0
(-1600 3985);
DISPLAY 0.617021 (-1600 3985);
PAINT PINK (-1600 3985);
FORCEPROP 2 LAST CDS_LIB mstr_standard
J 2
(-1600 3975);
DISPLAY 0.787234 (-1600 3975);
PAINT MONO (-1600 3975);
DISPLAY INVISIBLE (-1600 3975);
FORCEPROP 1 LAST BODY_TYPE PLUMBING
J 0
(-1600 3925);
DISPLAY 1.234043 (-1600 3925);
PAINT GREEN (-1600 3925);
DISPLAY INVISIBLE (-1600 3925);
FORCEPROP 1 LAST HDL_TAP TRUE
J 0
(-1275 3850);
DISPLAY 1.234043 (-1275 3850);
PAINT GREEN (-1275 3850);
DISPLAY INVISIBLE (-1275 3850);
FORCEPROP 1 LAST PATH I109
J 0
(-1602 3975);
DISPLAY 0.872340 (-1602 3975);
PAINT GREEN (-1602 3975);
DISPLAY INVISIBLE (-1602 3975);
FORCEADD OFFPAGE..1
(-2250 1025);
FORCEPROP 2 LAST $XR5 88 
J 0
(-2951 1025);
DISPLAY 0.638298 (-2951 1025);
PAINT MONO (-2951 1025);
FORCEPROP 2 LAST $XR4 87 
J 0
(-2861 1025);
DISPLAY 0.638298 (-2861 1025);
PAINT MONO (-2861 1025);
FORCEPROP 2 LAST $XR3 86 
J 0
(-2771 1025);
DISPLAY 0.638298 (-2771 1025);
PAINT MONO (-2771 1025);
FORCEPROP 2 LAST $XR2 85 
J 0
(-2681 1025);
DISPLAY 0.638298 (-2681 1025);
PAINT MONO (-2681 1025);
FORCEPROP 2 LAST $XR1 83 
J 0
(-2591 1025);
DISPLAY 0.638298 (-2591 1025);
PAINT MONO (-2591 1025);
FORCEPROP 2 LAST $XR0 89 
J 0
(-2501 1025);
DISPLAY 0.638298 (-2501 1025);
PAINT MONO (-2501 1025);
FORCEPROP 2 LAST CDS_LIB mstr_standard
J 0
(-2250 1025);
PAINT ORANGE (-2250 1025);
DISPLAY INVISIBLE (-2250 1025);
FORCEPROP 1 LAST OFFPAGE TRUE
J 0
(-1925 900);
DISPLAY 0.936170 (-1925 900);
PAINT GREEN (-1925 900);
DISPLAY INVISIBLE (-1925 900);
FORCEPROP 1 LAST COMMENT_BODY TRUE
J 0
(-2125 925);
DISPLAY 0.936170 (-2125 925);
PAINT GREEN (-2125 925);
DISPLAY INVISIBLE (-2125 925);
FORCEPROP 2 LAST PATH I11
J 0
(-2500 1075);
DISPLAY 1.021277 (-2500 1075);
PAINT ORANGE (-2500 1075);
DISPLAY INVISIBLE (-2500 1075);
FORCEADD TAP..6
(-1600 4025);
FORCEPROP 3 LASTPIN (-1550 4025) SIG_NAME M_K_MA<8>
J 0
(-1540 4035);
DISPLAY 0.659574 (-1540 4035);
PAINT MONO (-1540 4035);
DISPLAY INVISIBLE (-1540 4035);
FORCEPROP 1 LASTPIN (-1550 4025) BN 8
J 0
(-1600 4035);
DISPLAY 0.617021 (-1600 4035);
PAINT PINK (-1600 4035);
FORCEPROP 2 LAST CDS_LIB mstr_standard
J 2
(-1600 4025);
DISPLAY 0.787234 (-1600 4025);
PAINT MONO (-1600 4025);
DISPLAY INVISIBLE (-1600 4025);
FORCEPROP 1 LAST BODY_TYPE PLUMBING
J 0
(-1600 3975);
DISPLAY 1.234043 (-1600 3975);
PAINT GREEN (-1600 3975);
DISPLAY INVISIBLE (-1600 3975);
FORCEPROP 1 LAST HDL_TAP TRUE
J 0
(-1275 3900);
DISPLAY 1.234043 (-1275 3900);
PAINT GREEN (-1275 3900);
DISPLAY INVISIBLE (-1275 3900);
FORCEPROP 1 LAST PATH I110
J 0
(-1602 4025);
DISPLAY 0.872340 (-1602 4025);
PAINT GREEN (-1602 4025);
DISPLAY INVISIBLE (-1602 4025);
FORCEADD TAP..6
(-1600 4075);
FORCEPROP 3 LASTPIN (-1550 4075) SIG_NAME M_K_MA<9>
J 0
(-1540 4085);
DISPLAY 0.659574 (-1540 4085);
PAINT MONO (-1540 4085);
DISPLAY INVISIBLE (-1540 4085);
FORCEPROP 1 LASTPIN (-1550 4075) BN 9
J 0
(-1600 4085);
DISPLAY 0.617021 (-1600 4085);
PAINT PINK (-1600 4085);
FORCEPROP 2 LAST CDS_LIB mstr_standard
J 2
(-1600 4075);
DISPLAY 0.787234 (-1600 4075);
PAINT MONO (-1600 4075);
DISPLAY INVISIBLE (-1600 4075);
FORCEPROP 1 LAST BODY_TYPE PLUMBING
J 0
(-1600 4025);
DISPLAY 1.234043 (-1600 4025);
PAINT GREEN (-1600 4025);
DISPLAY INVISIBLE (-1600 4025);
FORCEPROP 1 LAST HDL_TAP TRUE
J 0
(-1275 3950);
DISPLAY 1.234043 (-1275 3950);
PAINT GREEN (-1275 3950);
DISPLAY INVISIBLE (-1275 3950);
FORCEPROP 1 LAST PATH I111
J 0
(-1602 4075);
DISPLAY 0.872340 (-1602 4075);
PAINT GREEN (-1602 4075);
DISPLAY INVISIBLE (-1602 4075);
FORCEADD TAP..6
(-1600 4175);
FORCEPROP 3 LASTPIN (-1550 4175) SIG_NAME M_K_MA<11>
J 0
(-1540 4185);
DISPLAY 0.659574 (-1540 4185);
PAINT MONO (-1540 4185);
DISPLAY INVISIBLE (-1540 4185);
FORCEPROP 1 LASTPIN (-1550 4175) BN 11
J 0
(-1600 4185);
DISPLAY 0.617021 (-1600 4185);
PAINT PINK (-1600 4185);
FORCEPROP 2 LAST CDS_LIB mstr_standard
J 2
(-1600 4175);
DISPLAY 0.787234 (-1600 4175);
PAINT MONO (-1600 4175);
DISPLAY INVISIBLE (-1600 4175);
FORCEPROP 1 LAST BODY_TYPE PLUMBING
J 0
(-1600 4125);
DISPLAY 1.234043 (-1600 4125);
PAINT GREEN (-1600 4125);
DISPLAY INVISIBLE (-1600 4125);
FORCEPROP 1 LAST HDL_TAP TRUE
J 0
(-1275 4050);
DISPLAY 1.234043 (-1275 4050);
PAINT GREEN (-1275 4050);
DISPLAY INVISIBLE (-1275 4050);
FORCEPROP 1 LAST PATH I112
J 0
(-1602 4175);
DISPLAY 0.872340 (-1602 4175);
PAINT GREEN (-1602 4175);
DISPLAY INVISIBLE (-1602 4175);
FORCEADD TAP..6
(-1600 4125);
FORCEPROP 3 LASTPIN (-1550 4125) SIG_NAME M_K_MA<10>
J 0
(-1540 4135);
DISPLAY 0.659574 (-1540 4135);
PAINT MONO (-1540 4135);
DISPLAY INVISIBLE (-1540 4135);
FORCEPROP 1 LASTPIN (-1550 4125) BN 10
J 0
(-1600 4135);
DISPLAY 0.617021 (-1600 4135);
PAINT PINK (-1600 4135);
FORCEPROP 2 LAST CDS_LIB mstr_standard
J 2
(-1600 4125);
DISPLAY 0.787234 (-1600 4125);
PAINT MONO (-1600 4125);
DISPLAY INVISIBLE (-1600 4125);
FORCEPROP 1 LAST BODY_TYPE PLUMBING
J 0
(-1600 4075);
DISPLAY 1.234043 (-1600 4075);
PAINT GREEN (-1600 4075);
DISPLAY INVISIBLE (-1600 4075);
FORCEPROP 1 LAST HDL_TAP TRUE
J 0
(-1275 4000);
DISPLAY 1.234043 (-1275 4000);
PAINT GREEN (-1275 4000);
DISPLAY INVISIBLE (-1275 4000);
FORCEPROP 1 LAST PATH I113
J 0
(-1602 4125);
DISPLAY 0.872340 (-1602 4125);
PAINT GREEN (-1602 4125);
DISPLAY INVISIBLE (-1602 4125);
FORCEADD TAP..6
(-1600 4225);
FORCEPROP 3 LASTPIN (-1550 4225) SIG_NAME M_K_MA<12>
J 0
(-1540 4235);
DISPLAY 0.659574 (-1540 4235);
PAINT MONO (-1540 4235);
DISPLAY INVISIBLE (-1540 4235);
FORCEPROP 1 LASTPIN (-1550 4225) BN 12
J 0
(-1600 4235);
DISPLAY 0.617021 (-1600 4235);
PAINT PINK (-1600 4235);
FORCEPROP 2 LAST CDS_LIB mstr_standard
J 2
(-1600 4225);
DISPLAY 0.787234 (-1600 4225);
PAINT MONO (-1600 4225);
DISPLAY INVISIBLE (-1600 4225);
FORCEPROP 1 LAST BODY_TYPE PLUMBING
J 0
(-1600 4175);
DISPLAY 1.234043 (-1600 4175);
PAINT GREEN (-1600 4175);
DISPLAY INVISIBLE (-1600 4175);
FORCEPROP 1 LAST HDL_TAP TRUE
J 0
(-1275 4100);
DISPLAY 1.234043 (-1275 4100);
PAINT GREEN (-1275 4100);
DISPLAY INVISIBLE (-1275 4100);
FORCEPROP 1 LAST PATH I114
J 0
(-1602 4225);
DISPLAY 0.872340 (-1602 4225);
PAINT GREEN (-1602 4225);
DISPLAY INVISIBLE (-1602 4225);
FORCEADD TAP..6
(-1600 4275);
FORCEPROP 3 LASTPIN (-1550 4275) SIG_NAME M_K_MA<13>
J 0
(-1540 4285);
DISPLAY 0.659574 (-1540 4285);
PAINT MONO (-1540 4285);
DISPLAY INVISIBLE (-1540 4285);
FORCEPROP 1 LASTPIN (-1550 4275) BN 13
J 0
(-1600 4285);
DISPLAY 0.617021 (-1600 4285);
PAINT PINK (-1600 4285);
FORCEPROP 2 LAST CDS_LIB mstr_standard
J 2
(-1600 4275);
DISPLAY 0.787234 (-1600 4275);
PAINT MONO (-1600 4275);
DISPLAY INVISIBLE (-1600 4275);
FORCEPROP 1 LAST BODY_TYPE PLUMBING
J 0
(-1600 4225);
DISPLAY 1.234043 (-1600 4225);
PAINT GREEN (-1600 4225);
DISPLAY INVISIBLE (-1600 4225);
FORCEPROP 1 LAST HDL_TAP TRUE
J 0
(-1275 4150);
DISPLAY 1.234043 (-1275 4150);
PAINT GREEN (-1275 4150);
DISPLAY INVISIBLE (-1275 4150);
FORCEPROP 1 LAST PATH I115
J 0
(-1602 4275);
DISPLAY 0.872340 (-1602 4275);
PAINT GREEN (-1602 4275);
DISPLAY INVISIBLE (-1602 4275);
FORCEADD TAP..6
(-1600 4325);
FORCEPROP 3 LASTPIN (-1550 4325) SIG_NAME M_K_MA<14>
J 0
(-1540 4335);
DISPLAY 0.659574 (-1540 4335);
PAINT MONO (-1540 4335);
DISPLAY INVISIBLE (-1540 4335);
FORCEPROP 1 LASTPIN (-1550 4325) BN 14
J 0
(-1600 4335);
DISPLAY 0.617021 (-1600 4335);
PAINT PINK (-1600 4335);
FORCEPROP 2 LAST CDS_LIB mstr_standard
J 2
(-1600 4325);
DISPLAY 0.787234 (-1600 4325);
PAINT MONO (-1600 4325);
DISPLAY INVISIBLE (-1600 4325);
FORCEPROP 1 LAST BODY_TYPE PLUMBING
J 0
(-1600 4275);
DISPLAY 1.234043 (-1600 4275);
PAINT GREEN (-1600 4275);
DISPLAY INVISIBLE (-1600 4275);
FORCEPROP 1 LAST HDL_TAP TRUE
J 0
(-1275 4200);
DISPLAY 1.234043 (-1275 4200);
PAINT GREEN (-1275 4200);
DISPLAY INVISIBLE (-1275 4200);
FORCEPROP 1 LAST PATH I116
J 0
(-1602 4325);
DISPLAY 0.872340 (-1602 4325);
PAINT GREEN (-1602 4325);
DISPLAY INVISIBLE (-1602 4325);
FORCEADD TAP..6
(-1600 4425);
FORCEPROP 3 LASTPIN (-1550 4425) SIG_NAME M_K_MA<16>
J 0
(-1540 4435);
DISPLAY 0.659574 (-1540 4435);
PAINT MONO (-1540 4435);
DISPLAY INVISIBLE (-1540 4435);
FORCEPROP 1 LASTPIN (-1550 4425) BN 16
J 0
(-1600 4435);
DISPLAY 0.617021 (-1600 4435);
PAINT PINK (-1600 4435);
FORCEPROP 2 LAST CDS_LIB mstr_standard
J 2
(-1600 4425);
DISPLAY 0.787234 (-1600 4425);
PAINT MONO (-1600 4425);
DISPLAY INVISIBLE (-1600 4425);
FORCEPROP 1 LAST BODY_TYPE PLUMBING
J 0
(-1600 4375);
DISPLAY 1.234043 (-1600 4375);
PAINT GREEN (-1600 4375);
DISPLAY INVISIBLE (-1600 4375);
FORCEPROP 1 LAST HDL_TAP TRUE
J 0
(-1275 4300);
DISPLAY 1.234043 (-1275 4300);
PAINT GREEN (-1275 4300);
DISPLAY INVISIBLE (-1275 4300);
FORCEPROP 1 LAST PATH I117
J 0
(-1602 4425);
DISPLAY 0.872340 (-1602 4425);
PAINT GREEN (-1602 4425);
DISPLAY INVISIBLE (-1602 4425);
FORCEADD TAP..6
(-1600 4375);
FORCEPROP 3 LASTPIN (-1550 4375) SIG_NAME M_K_MA<15>
J 0
(-1540 4385);
DISPLAY 0.659574 (-1540 4385);
PAINT MONO (-1540 4385);
DISPLAY INVISIBLE (-1540 4385);
FORCEPROP 1 LASTPIN (-1550 4375) BN 15
J 0
(-1600 4385);
DISPLAY 0.617021 (-1600 4385);
PAINT PINK (-1600 4385);
FORCEPROP 2 LAST CDS_LIB mstr_standard
J 2
(-1600 4375);
DISPLAY 0.787234 (-1600 4375);
PAINT MONO (-1600 4375);
DISPLAY INVISIBLE (-1600 4375);
FORCEPROP 1 LAST BODY_TYPE PLUMBING
J 0
(-1600 4325);
DISPLAY 1.234043 (-1600 4325);
PAINT GREEN (-1600 4325);
DISPLAY INVISIBLE (-1600 4325);
FORCEPROP 1 LAST HDL_TAP TRUE
J 0
(-1275 4250);
DISPLAY 1.234043 (-1275 4250);
PAINT GREEN (-1275 4250);
DISPLAY INVISIBLE (-1275 4250);
FORCEPROP 1 LAST PATH I118
J 0
(-1602 4375);
DISPLAY 0.872340 (-1602 4375);
PAINT GREEN (-1602 4375);
DISPLAY INVISIBLE (-1602 4375);
FORCEADD TAP..6
(-1600 4475);
FORCEPROP 3 LASTPIN (-1550 4475) SIG_NAME M_K_MA<17>
J 0
(-1540 4485);
DISPLAY 0.659574 (-1540 4485);
PAINT MONO (-1540 4485);
DISPLAY INVISIBLE (-1540 4485);
FORCEPROP 1 LASTPIN (-1550 4475) BN 17
J 0
(-1600 4485);
DISPLAY 0.617021 (-1600 4485);
PAINT PINK (-1600 4485);
FORCEPROP 2 LAST CDS_LIB mstr_standard
J 0
(-1600 4475);
DISPLAY 0.787234 (-1600 4475);
PAINT MONO (-1600 4475);
DISPLAY INVISIBLE (-1600 4475);
FORCEPROP 1 LAST BODY_TYPE PLUMBING
J 0
(-1600 4425);
DISPLAY 1.234043 (-1600 4425);
PAINT GREEN (-1600 4425);
DISPLAY INVISIBLE (-1600 4425);
FORCEPROP 1 LAST HDL_TAP TRUE
J 0
(-1275 4350);
DISPLAY 1.234043 (-1275 4350);
PAINT GREEN (-1275 4350);
DISPLAY INVISIBLE (-1275 4350);
FORCEPROP 1 LAST PATH I119
J 0
(-1602 4475);
DISPLAY 0.872340 (-1602 4475);
PAINT GREEN (-1602 4475);
DISPLAY INVISIBLE (-1602 4475);
FORCEADD OFFPAGE..1
(-2200 1425);
FORCEPROP 2 LAST $XR5 88 
J 0
(-2901 1425);
DISPLAY 0.638298 (-2901 1425);
PAINT MONO (-2901 1425);
FORCEPROP 2 LAST $XR4 87 
J 0
(-2811 1425);
DISPLAY 0.638298 (-2811 1425);
PAINT MONO (-2811 1425);
FORCEPROP 2 LAST $XR3 86 
J 0
(-2721 1425);
DISPLAY 0.638298 (-2721 1425);
PAINT MONO (-2721 1425);
FORCEPROP 2 LAST $XR2 85 
J 0
(-2631 1425);
DISPLAY 0.638298 (-2631 1425);
PAINT MONO (-2631 1425);
FORCEPROP 2 LAST $XR1 83 
J 0
(-2541 1425);
DISPLAY 0.638298 (-2541 1425);
PAINT MONO (-2541 1425);
FORCEPROP 2 LAST $XR0 99 
J 0
(-2451 1425);
DISPLAY 0.638298 (-2451 1425);
PAINT MONO (-2451 1425);
FORCEPROP 2 LAST CDS_LIB mstr_standard
J 0
(-2200 1425);
DISPLAY 0.787234 (-2200 1425);
PAINT MONO (-2200 1425);
DISPLAY INVISIBLE (-2200 1425);
FORCEPROP 1 LAST OFFPAGE TRUE
J 0
(-1875 1300);
DISPLAY 0.936170 (-1875 1300);
PAINT GREEN (-1875 1300);
DISPLAY INVISIBLE (-1875 1300);
FORCEPROP 1 LAST COMMENT_BODY TRUE
J 0
(-2075 1325);
DISPLAY 0.936170 (-2075 1325);
PAINT GREEN (-2075 1325);
DISPLAY INVISIBLE (-2075 1325);
FORCEPROP 2 LAST PATH I12
J 0
(-2450 1475);
DISPLAY 1.021277 (-2450 1475);
PAINT ORANGE (-2450 1475);
DISPLAY INVISIBLE (-2450 1475);
FORCEADD TAP..6
R 2
(-100 3825);
FORCEPROP 3 LASTPIN (-150 3825) SIG_NAME M_K_DQ<50>
J 0
(-140 3835);
DISPLAY 0.659574 (-140 3835);
PAINT MONO (-140 3835);
DISPLAY INVISIBLE (-140 3835);
FORCEPROP 1 LASTPIN (-150 3825) BN 50
J 2
(-100 3835);
DISPLAY 0.617021 (-100 3835);
PAINT PINK (-100 3835);
FORCEPROP 2 LAST CDS_LIB mstr_standard
J 2
(-100 3825);
DISPLAY 0.787234 (-100 3825);
PAINT MONO (-100 3825);
DISPLAY INVISIBLE (-100 3825);
FORCEPROP 1 LAST BODY_TYPE PLUMBING
J 2
(-100 3775);
DISPLAY 1.234043 (-100 3775);
PAINT GREEN (-100 3775);
DISPLAY INVISIBLE (-100 3775);
FORCEPROP 1 LAST HDL_TAP TRUE
J 2
(-425 3700);
DISPLAY 1.234043 (-425 3700);
PAINT GREEN (-425 3700);
DISPLAY INVISIBLE (-425 3700);
FORCEPROP 1 LAST PATH I120
J 2
(-98 3825);
DISPLAY 0.872340 (-98 3825);
PAINT GREEN (-98 3825);
DISPLAY INVISIBLE (-98 3825);
FORCEADD TAP..6
R 2
(-100 3725);
FORCEPROP 3 LASTPIN (-150 3725) SIG_NAME M_K_DQ<48>
J 0
(-140 3735);
DISPLAY 0.659574 (-140 3735);
PAINT MONO (-140 3735);
DISPLAY INVISIBLE (-140 3735);
FORCEPROP 1 LASTPIN (-150 3725) BN 48
J 2
(-100 3735);
DISPLAY 0.617021 (-100 3735);
PAINT PINK (-100 3735);
FORCEPROP 2 LAST CDS_LIB mstr_standard
J 2
(-100 3725);
DISPLAY 0.787234 (-100 3725);
PAINT MONO (-100 3725);
DISPLAY INVISIBLE (-100 3725);
FORCEPROP 1 LAST BODY_TYPE PLUMBING
J 2
(-100 3675);
DISPLAY 1.234043 (-100 3675);
PAINT GREEN (-100 3675);
DISPLAY INVISIBLE (-100 3675);
FORCEPROP 1 LAST HDL_TAP TRUE
J 2
(-425 3600);
DISPLAY 1.234043 (-425 3600);
PAINT GREEN (-425 3600);
DISPLAY INVISIBLE (-425 3600);
FORCEPROP 1 LAST PATH I121
J 2
(-98 3725);
DISPLAY 0.872340 (-98 3725);
PAINT GREEN (-98 3725);
DISPLAY INVISIBLE (-98 3725);
FORCEADD TAP..6
R 2
(-100 3775);
FORCEPROP 3 LASTPIN (-150 3775) SIG_NAME M_K_DQ<49>
J 0
(-140 3785);
DISPLAY 0.659574 (-140 3785);
PAINT MONO (-140 3785);
DISPLAY INVISIBLE (-140 3785);
FORCEPROP 1 LASTPIN (-150 3775) BN 49
J 2
(-100 3785);
DISPLAY 0.617021 (-100 3785);
PAINT PINK (-100 3785);
FORCEPROP 2 LAST CDS_LIB mstr_standard
J 2
(-100 3775);
DISPLAY 0.787234 (-100 3775);
PAINT MONO (-100 3775);
DISPLAY INVISIBLE (-100 3775);
FORCEPROP 1 LAST BODY_TYPE PLUMBING
J 2
(-100 3725);
DISPLAY 1.234043 (-100 3725);
PAINT GREEN (-100 3725);
DISPLAY INVISIBLE (-100 3725);
FORCEPROP 1 LAST HDL_TAP TRUE
J 2
(-425 3650);
DISPLAY 1.234043 (-425 3650);
PAINT GREEN (-425 3650);
DISPLAY INVISIBLE (-425 3650);
FORCEPROP 1 LAST PATH I122
J 2
(-98 3775);
DISPLAY 0.872340 (-98 3775);
PAINT GREEN (-98 3775);
DISPLAY INVISIBLE (-98 3775);
FORCEADD TAP..6
R 2
(-100 3975);
FORCEPROP 3 LASTPIN (-150 3975) SIG_NAME M_K_DQ<53>
J 0
(-140 3985);
DISPLAY 0.659574 (-140 3985);
PAINT MONO (-140 3985);
DISPLAY INVISIBLE (-140 3985);
FORCEPROP 1 LASTPIN (-150 3975) BN 53
J 2
(-100 3985);
DISPLAY 0.617021 (-100 3985);
PAINT PINK (-100 3985);
FORCEPROP 2 LAST CDS_LIB mstr_standard
J 2
(-100 3975);
DISPLAY 0.787234 (-100 3975);
PAINT MONO (-100 3975);
DISPLAY INVISIBLE (-100 3975);
FORCEPROP 1 LAST BODY_TYPE PLUMBING
J 2
(-100 3925);
DISPLAY 1.234043 (-100 3925);
PAINT GREEN (-100 3925);
DISPLAY INVISIBLE (-100 3925);
FORCEPROP 1 LAST HDL_TAP TRUE
J 2
(-425 3850);
DISPLAY 1.234043 (-425 3850);
PAINT GREEN (-425 3850);
DISPLAY INVISIBLE (-425 3850);
FORCEPROP 1 LAST PATH I123
J 2
(-98 3975);
DISPLAY 0.872340 (-98 3975);
PAINT GREEN (-98 3975);
DISPLAY INVISIBLE (-98 3975);
FORCEADD TAP..6
R 2
(-100 3925);
FORCEPROP 3 LASTPIN (-150 3925) SIG_NAME M_K_DQ<52>
J 0
(-140 3935);
DISPLAY 0.659574 (-140 3935);
PAINT MONO (-140 3935);
DISPLAY INVISIBLE (-140 3935);
FORCEPROP 1 LASTPIN (-150 3925) BN 52
J 2
(-100 3935);
DISPLAY 0.617021 (-100 3935);
PAINT PINK (-100 3935);
FORCEPROP 2 LAST CDS_LIB mstr_standard
J 2
(-100 3925);
DISPLAY 0.787234 (-100 3925);
PAINT MONO (-100 3925);
DISPLAY INVISIBLE (-100 3925);
FORCEPROP 1 LAST BODY_TYPE PLUMBING
J 2
(-100 3875);
DISPLAY 1.234043 (-100 3875);
PAINT GREEN (-100 3875);
DISPLAY INVISIBLE (-100 3875);
FORCEPROP 1 LAST HDL_TAP TRUE
J 2
(-425 3800);
DISPLAY 1.234043 (-425 3800);
PAINT GREEN (-425 3800);
DISPLAY INVISIBLE (-425 3800);
FORCEPROP 1 LAST PATH I124
J 2
(-98 3925);
DISPLAY 0.872340 (-98 3925);
PAINT GREEN (-98 3925);
DISPLAY INVISIBLE (-98 3925);
FORCEADD TAP..6
R 2
(-100 3875);
FORCEPROP 3 LASTPIN (-150 3875) SIG_NAME M_K_DQ<51>
J 0
(-140 3885);
DISPLAY 0.659574 (-140 3885);
PAINT MONO (-140 3885);
DISPLAY INVISIBLE (-140 3885);
FORCEPROP 1 LASTPIN (-150 3875) BN 51
J 2
(-100 3885);
DISPLAY 0.617021 (-100 3885);
PAINT PINK (-100 3885);
FORCEPROP 2 LAST CDS_LIB mstr_standard
J 2
(-100 3875);
DISPLAY 0.787234 (-100 3875);
PAINT MONO (-100 3875);
DISPLAY INVISIBLE (-100 3875);
FORCEPROP 1 LAST BODY_TYPE PLUMBING
J 2
(-100 3825);
DISPLAY 1.234043 (-100 3825);
PAINT GREEN (-100 3825);
DISPLAY INVISIBLE (-100 3825);
FORCEPROP 1 LAST HDL_TAP TRUE
J 2
(-425 3750);
DISPLAY 1.234043 (-425 3750);
PAINT GREEN (-425 3750);
DISPLAY INVISIBLE (-425 3750);
FORCEPROP 1 LAST PATH I125
J 2
(-98 3875);
DISPLAY 0.872340 (-98 3875);
PAINT GREEN (-98 3875);
DISPLAY INVISIBLE (-98 3875);
FORCEADD TAP..6
R 2
(-100 4075);
FORCEPROP 3 LASTPIN (-150 4075) SIG_NAME M_K_DQ<55>
J 0
(-140 4085);
DISPLAY 0.659574 (-140 4085);
PAINT MONO (-140 4085);
DISPLAY INVISIBLE (-140 4085);
FORCEPROP 1 LASTPIN (-150 4075) BN 55
J 2
(-100 4085);
DISPLAY 0.617021 (-100 4085);
PAINT PINK (-100 4085);
FORCEPROP 2 LAST CDS_LIB mstr_standard
J 2
(-100 4075);
DISPLAY 0.787234 (-100 4075);
PAINT MONO (-100 4075);
DISPLAY INVISIBLE (-100 4075);
FORCEPROP 1 LAST BODY_TYPE PLUMBING
J 2
(-100 4025);
DISPLAY 1.234043 (-100 4025);
PAINT GREEN (-100 4025);
DISPLAY INVISIBLE (-100 4025);
FORCEPROP 1 LAST HDL_TAP TRUE
J 2
(-425 3950);
DISPLAY 1.234043 (-425 3950);
PAINT GREEN (-425 3950);
DISPLAY INVISIBLE (-425 3950);
FORCEPROP 1 LAST PATH I126
J 2
(-98 4075);
DISPLAY 0.872340 (-98 4075);
PAINT GREEN (-98 4075);
DISPLAY INVISIBLE (-98 4075);
FORCEADD TAP..6
R 2
(-100 4025);
FORCEPROP 3 LASTPIN (-150 4025) SIG_NAME M_K_DQ<54>
J 0
(-140 4035);
DISPLAY 0.659574 (-140 4035);
PAINT MONO (-140 4035);
DISPLAY INVISIBLE (-140 4035);
FORCEPROP 1 LASTPIN (-150 4025) BN 54
J 2
(-100 4035);
DISPLAY 0.617021 (-100 4035);
PAINT PINK (-100 4035);
FORCEPROP 2 LAST CDS_LIB mstr_standard
J 2
(-100 4025);
DISPLAY 0.787234 (-100 4025);
PAINT MONO (-100 4025);
DISPLAY INVISIBLE (-100 4025);
FORCEPROP 1 LAST BODY_TYPE PLUMBING
J 2
(-100 3975);
DISPLAY 1.234043 (-100 3975);
PAINT GREEN (-100 3975);
DISPLAY INVISIBLE (-100 3975);
FORCEPROP 1 LAST HDL_TAP TRUE
J 2
(-425 3900);
DISPLAY 1.234043 (-425 3900);
PAINT GREEN (-425 3900);
DISPLAY INVISIBLE (-425 3900);
FORCEPROP 1 LAST PATH I127
J 2
(-98 4025);
DISPLAY 0.872340 (-98 4025);
PAINT GREEN (-98 4025);
DISPLAY INVISIBLE (-98 4025);
FORCEADD TAP..6
R 2
(-100 4175);
FORCEPROP 3 LASTPIN (-150 4175) SIG_NAME M_K_DQ<57>
J 0
(-140 4185);
DISPLAY 0.659574 (-140 4185);
PAINT MONO (-140 4185);
DISPLAY INVISIBLE (-140 4185);
FORCEPROP 1 LASTPIN (-150 4175) BN 57
J 2
(-100 4185);
DISPLAY 0.617021 (-100 4185);
PAINT PINK (-100 4185);
FORCEPROP 2 LAST CDS_LIB mstr_standard
J 2
(-100 4175);
DISPLAY 0.787234 (-100 4175);
PAINT MONO (-100 4175);
DISPLAY INVISIBLE (-100 4175);
FORCEPROP 1 LAST BODY_TYPE PLUMBING
J 2
(-100 4125);
DISPLAY 1.234043 (-100 4125);
PAINT GREEN (-100 4125);
DISPLAY INVISIBLE (-100 4125);
FORCEPROP 1 LAST HDL_TAP TRUE
J 2
(-425 4050);
DISPLAY 1.234043 (-425 4050);
PAINT GREEN (-425 4050);
DISPLAY INVISIBLE (-425 4050);
FORCEPROP 1 LAST PATH I128
J 2
(-98 4175);
DISPLAY 0.872340 (-98 4175);
PAINT GREEN (-98 4175);
DISPLAY INVISIBLE (-98 4175);
FORCEADD TAP..6
R 2
(-100 4225);
FORCEPROP 3 LASTPIN (-150 4225) SIG_NAME M_K_DQ<58>
J 0
(-140 4235);
DISPLAY 0.659574 (-140 4235);
PAINT MONO (-140 4235);
DISPLAY INVISIBLE (-140 4235);
FORCEPROP 1 LASTPIN (-150 4225) BN 58
J 2
(-100 4235);
DISPLAY 0.617021 (-100 4235);
PAINT PINK (-100 4235);
FORCEPROP 2 LAST CDS_LIB mstr_standard
J 2
(-100 4225);
DISPLAY 0.787234 (-100 4225);
PAINT MONO (-100 4225);
DISPLAY INVISIBLE (-100 4225);
FORCEPROP 1 LAST BODY_TYPE PLUMBING
J 2
(-100 4175);
DISPLAY 1.234043 (-100 4175);
PAINT GREEN (-100 4175);
DISPLAY INVISIBLE (-100 4175);
FORCEPROP 1 LAST HDL_TAP TRUE
J 2
(-425 4100);
DISPLAY 1.234043 (-425 4100);
PAINT GREEN (-425 4100);
DISPLAY INVISIBLE (-425 4100);
FORCEPROP 1 LAST PATH I129
J 2
(-98 4225);
DISPLAY 0.872340 (-98 4225);
PAINT GREEN (-98 4225);
DISPLAY INVISIBLE (-98 4225);
FORCEADD OFFPAGE..6
(-2200 1475);
FORCEPROP 2 LASTPIN (-2150 1475) SIG_NAME SMB_DDR_KLM_VPP_SDA
J 0
(-2110 1485);
DISPLAY 0.617021 (-2110 1485);
PAINT ORANGE (-2110 1485);
FORCEPROP 2 LAST $XR5 99 
J 0
(-2899 1475);
DISPLAY 0.638298 (-2899 1475);
PAINT MONO (-2899 1475);
FORCEPROP 2 LAST $XR4 88 
J 0
(-2809 1475);
DISPLAY 0.638298 (-2809 1475);
PAINT MONO (-2809 1475);
FORCEPROP 2 LAST $XR3 87 
J 0
(-2719 1475);
DISPLAY 0.638298 (-2719 1475);
PAINT MONO (-2719 1475);
FORCEPROP 2 LAST $XR2 86 
J 0
(-2629 1475);
DISPLAY 0.638298 (-2629 1475);
PAINT MONO (-2629 1475);
FORCEPROP 2 LAST $XR1 85 
J 0
(-2539 1475);
DISPLAY 0.638298 (-2539 1475);
PAINT MONO (-2539 1475);
FORCEPROP 2 LAST $XR0 83 
J 0
(-2449 1475);
DISPLAY 0.638298 (-2449 1475);
PAINT MONO (-2449 1475);
FORCEPROP 2 LAST CDS_LIB mstr_standard
J 0
(-2200 1475);
DISPLAY 0.787234 (-2200 1475);
PAINT MONO (-2200 1475);
DISPLAY INVISIBLE (-2200 1475);
FORCEPROP 1 LAST OFFPAGE TRUE
J 0
(-1875 1350);
DISPLAY 0.936170 (-1875 1350);
PAINT GREEN (-1875 1350);
DISPLAY INVISIBLE (-1875 1350);
FORCEPROP 1 LAST COMMENT_BODY TRUE
J 0
(-2100 1400);
DISPLAY 0.936170 (-2100 1400);
PAINT GREEN (-2100 1400);
DISPLAY INVISIBLE (-2100 1400);
FORCEPROP 2 LAST PATH I13
J 0
(-2425 1525);
DISPLAY 1.021277 (-2425 1525);
PAINT ORANGE (-2425 1525);
DISPLAY INVISIBLE (-2425 1525);
FORCEADD TAP..6
R 2
(-100 4125);
FORCEPROP 3 LASTPIN (-150 4125) SIG_NAME M_K_DQ<56>
J 0
(-140 4135);
DISPLAY 0.659574 (-140 4135);
PAINT MONO (-140 4135);
DISPLAY INVISIBLE (-140 4135);
FORCEPROP 1 LASTPIN (-150 4125) BN 56
J 2
(-100 4135);
DISPLAY 0.617021 (-100 4135);
PAINT PINK (-100 4135);
FORCEPROP 2 LAST CDS_LIB mstr_standard
J 2
(-100 4125);
DISPLAY 0.787234 (-100 4125);
PAINT MONO (-100 4125);
DISPLAY INVISIBLE (-100 4125);
FORCEPROP 1 LAST BODY_TYPE PLUMBING
J 2
(-100 4075);
DISPLAY 1.234043 (-100 4075);
PAINT GREEN (-100 4075);
DISPLAY INVISIBLE (-100 4075);
FORCEPROP 1 LAST HDL_TAP TRUE
J 2
(-425 4000);
DISPLAY 1.234043 (-425 4000);
PAINT GREEN (-425 4000);
DISPLAY INVISIBLE (-425 4000);
FORCEPROP 1 LAST PATH I130
J 2
(-98 4125);
DISPLAY 0.872340 (-98 4125);
PAINT GREEN (-98 4125);
DISPLAY INVISIBLE (-98 4125);
FORCEADD TAP..6
R 2
(-100 4275);
FORCEPROP 3 LASTPIN (-150 4275) SIG_NAME M_K_DQ<59>
J 0
(-140 4285);
DISPLAY 0.659574 (-140 4285);
PAINT MONO (-140 4285);
DISPLAY INVISIBLE (-140 4285);
FORCEPROP 1 LASTPIN (-150 4275) BN 59
J 2
(-100 4285);
DISPLAY 0.617021 (-100 4285);
PAINT PINK (-100 4285);
FORCEPROP 2 LAST CDS_LIB mstr_standard
J 2
(-100 4275);
DISPLAY 0.787234 (-100 4275);
PAINT MONO (-100 4275);
DISPLAY INVISIBLE (-100 4275);
FORCEPROP 1 LAST BODY_TYPE PLUMBING
J 2
(-100 4225);
DISPLAY 1.234043 (-100 4225);
PAINT GREEN (-100 4225);
DISPLAY INVISIBLE (-100 4225);
FORCEPROP 1 LAST HDL_TAP TRUE
J 2
(-425 4150);
DISPLAY 1.234043 (-425 4150);
PAINT GREEN (-425 4150);
DISPLAY INVISIBLE (-425 4150);
FORCEPROP 1 LAST PATH I131
J 2
(-98 4275);
DISPLAY 0.872340 (-98 4275);
PAINT GREEN (-98 4275);
DISPLAY INVISIBLE (-98 4275);
FORCEADD TAP..6
R 2
(-100 4325);
FORCEPROP 3 LASTPIN (-150 4325) SIG_NAME M_K_DQ<60>
J 0
(-140 4335);
DISPLAY 0.659574 (-140 4335);
PAINT MONO (-140 4335);
DISPLAY INVISIBLE (-140 4335);
FORCEPROP 1 LASTPIN (-150 4325) BN 60
J 2
(-100 4335);
DISPLAY 0.617021 (-100 4335);
PAINT PINK (-100 4335);
FORCEPROP 2 LAST CDS_LIB mstr_standard
J 2
(-100 4325);
DISPLAY 0.787234 (-100 4325);
PAINT MONO (-100 4325);
DISPLAY INVISIBLE (-100 4325);
FORCEPROP 1 LAST BODY_TYPE PLUMBING
J 2
(-100 4275);
DISPLAY 1.234043 (-100 4275);
PAINT GREEN (-100 4275);
DISPLAY INVISIBLE (-100 4275);
FORCEPROP 1 LAST HDL_TAP TRUE
J 2
(-425 4200);
DISPLAY 1.234043 (-425 4200);
PAINT GREEN (-425 4200);
DISPLAY INVISIBLE (-425 4200);
FORCEPROP 1 LAST PATH I132
J 2
(-98 4325);
DISPLAY 0.872340 (-98 4325);
PAINT GREEN (-98 4325);
DISPLAY INVISIBLE (-98 4325);
FORCEADD TAP..6
R 2
(-100 4475);
FORCEPROP 3 LASTPIN (-150 4475) SIG_NAME M_K_DQ<63>
J 0
(-140 4485);
DISPLAY 0.659574 (-140 4485);
PAINT MONO (-140 4485);
DISPLAY INVISIBLE (-140 4485);
FORCEPROP 1 LASTPIN (-150 4475) BN 63
J 2
(-100 4485);
DISPLAY 0.617021 (-100 4485);
PAINT PINK (-100 4485);
FORCEPROP 2 LAST CDS_LIB mstr_standard
J 2
(-100 4475);
DISPLAY 0.787234 (-100 4475);
PAINT MONO (-100 4475);
DISPLAY INVISIBLE (-100 4475);
FORCEPROP 1 LAST BODY_TYPE PLUMBING
J 2
(-100 4425);
DISPLAY 1.234043 (-100 4425);
PAINT GREEN (-100 4425);
DISPLAY INVISIBLE (-100 4425);
FORCEPROP 1 LAST HDL_TAP TRUE
J 2
(-425 4350);
DISPLAY 1.234043 (-425 4350);
PAINT GREEN (-425 4350);
DISPLAY INVISIBLE (-425 4350);
FORCEPROP 1 LAST PATH I133
J 2
(-98 4475);
DISPLAY 0.872340 (-98 4475);
PAINT GREEN (-98 4475);
DISPLAY INVISIBLE (-98 4475);
FORCEADD TAP..6
R 2
(-100 4425);
FORCEPROP 3 LASTPIN (-150 4425) SIG_NAME M_K_DQ<62>
J 0
(-140 4435);
DISPLAY 0.659574 (-140 4435);
PAINT MONO (-140 4435);
DISPLAY INVISIBLE (-140 4435);
FORCEPROP 1 LASTPIN (-150 4425) BN 62
J 2
(-100 4435);
DISPLAY 0.617021 (-100 4435);
PAINT PINK (-100 4435);
FORCEPROP 2 LAST CDS_LIB mstr_standard
J 2
(-100 4425);
DISPLAY 0.787234 (-100 4425);
PAINT MONO (-100 4425);
DISPLAY INVISIBLE (-100 4425);
FORCEPROP 1 LAST BODY_TYPE PLUMBING
J 2
(-100 4375);
DISPLAY 1.234043 (-100 4375);
PAINT GREEN (-100 4375);
DISPLAY INVISIBLE (-100 4375);
FORCEPROP 1 LAST HDL_TAP TRUE
J 2
(-425 4300);
DISPLAY 1.234043 (-425 4300);
PAINT GREEN (-425 4300);
DISPLAY INVISIBLE (-425 4300);
FORCEPROP 1 LAST PATH I134
J 2
(-98 4425);
DISPLAY 0.872340 (-98 4425);
PAINT GREEN (-98 4425);
DISPLAY INVISIBLE (-98 4425);
FORCEADD TAP..6
R 2
(-100 4375);
FORCEPROP 3 LASTPIN (-150 4375) SIG_NAME M_K_DQ<61>
J 0
(-140 4385);
DISPLAY 0.659574 (-140 4385);
PAINT MONO (-140 4385);
DISPLAY INVISIBLE (-140 4385);
FORCEPROP 1 LASTPIN (-150 4375) BN 61
J 2
(-100 4385);
DISPLAY 0.617021 (-100 4385);
PAINT PINK (-100 4385);
FORCEPROP 2 LAST CDS_LIB mstr_standard
J 2
(-100 4375);
DISPLAY 0.787234 (-100 4375);
PAINT MONO (-100 4375);
DISPLAY INVISIBLE (-100 4375);
FORCEPROP 1 LAST BODY_TYPE PLUMBING
J 2
(-100 4325);
DISPLAY 1.234043 (-100 4325);
PAINT GREEN (-100 4325);
DISPLAY INVISIBLE (-100 4325);
FORCEPROP 1 LAST HDL_TAP TRUE
J 2
(-425 4250);
DISPLAY 1.234043 (-425 4250);
PAINT GREEN (-425 4250);
DISPLAY INVISIBLE (-425 4250);
FORCEPROP 1 LAST PATH I135
J 2
(-98 4375);
DISPLAY 0.872340 (-98 4375);
PAINT GREEN (-98 4375);
DISPLAY INVISIBLE (-98 4375);
FORCEADD OFFPAGE..3
(500 4525);
FORCEPROP 2 LAST $XR1 83 
J 0
(804 4525);
DISPLAY 0.638298 (804 4525);
PAINT MONO (804 4525);
FORCEPROP 2 LAST $XR0 60 
J 0
(714 4525);
DISPLAY 0.638298 (714 4525);
PAINT MONO (714 4525);
FORCEPROP 2 LAST CDS_LIB mstr_standard
J 0
(500 4525);
DISPLAY 0.787234 (500 4525);
PAINT MONO (500 4525);
DISPLAY INVISIBLE (500 4525);
FORCEPROP 1 LAST OFFPAGE TRUE
J 0
(825 4400);
DISPLAY 0.936170 (825 4400);
PAINT GREEN (825 4400);
DISPLAY INVISIBLE (825 4400);
FORCEPROP 1 LAST COMMENT_BODY TRUE
J 0
(450 4425);
DISPLAY 0.936170 (450 4425);
PAINT GREEN (450 4425);
DISPLAY INVISIBLE (450 4425);
FORCEPROP 2 LAST PATH I136
J 0
(725 4575);
DISPLAY 1.021277 (725 4575);
PAINT ORANGE (725 4575);
DISPLAY INVISIBLE (725 4575);
FORCEADD GND..1
R 2
(2700 725);
FORCEPROP 3 LASTPIN (2700 775) SIG_NAME GND\g
J 0
(2710 785);
DISPLAY 0.659574 (2710 785);
PAINT MONO (2710 785);
DISPLAY INVISIBLE (2710 785);
FORCEPROP 1 LAST VOLTAGE 0
J 0
(2700 725);
PAINT SKYBLUE (2700 725);
DISPLAY INVISIBLE (2700 725);
FORCEPROP 2 LAST CDS_LIB mstr_symbols
J 0
(2700 725);
DISPLAY 0.787234 (2700 725);
PAINT MONO (2700 725);
DISPLAY INVISIBLE (2700 725);
FORCEPROP 1 LAST SIZE 1B
J 2
(2625 675);
DISPLAY 1.170213 (2625 675);
PAINT GREEN (2625 675);
DISPLAY INVISIBLE (2625 675);
FORCEPROP 2 LAST BOM_COST MEM
J 0
(2700 730);
PAINT ORANGE (2700 730);
DISPLAY INVISIBLE (2700 730);
FORCEPROP 1 LAST BODY_TYPE PLUMBING
J 2
(2745 682);
DISPLAY 0.340426 (2745 682);
PAINT GREEN (2745 682);
DISPLAY INVISIBLE (2745 682);
FORCEPROP 1 LAST PATH I137
J 2
(2625 725);
DISPLAY 0.872340 (2625 725);
PAINT AQUA (2625 725);
DISPLAY INVISIBLE (2625 725);
FORCEPROP 2 LAST ROOM DDR4_CH_C
J 0
(2700 730);
PAINT ORANGE (2700 730);
DISPLAY INVISIBLE (2700 730);
FORCEPROP 1 LAST HDL_POWER GND
J 2
(2700 875);
DISPLAY 0.553191 (2700 875);
PAINT GREEN (2700 875);
DISPLAY INVISIBLE (2700 875);
FORCEADD SCONN288_H44441003..3
(3400 2025);
FORCEPROP 1 LAST LOCATION J9M1
J 0
(2950 3425);
DISPLAY 0.617021 (2950 3425);
PAINT AQUA (2950 3425);
FORCEPROP 1 LAST PART_NUMBER H44441-003
J 0
(2950 675);
DISPLAY 0.617021 (2950 675);
PAINT BLUE (2950 675);
FORCEPROP 2 LASTPIN (2900 3175) $PN 2
J 2
(2890 3185);
DISPLAY 0.617021 (2890 3185);
PAINT ORANGE (2890 3185);
FORCEPROP 2 LASTPIN (2900 3125) $PN 4
J 2
(2890 3135);
DISPLAY 0.617021 (2890 3135);
PAINT ORANGE (2890 3135);
FORCEPROP 2 LASTPIN (2900 3075) $PN 6
J 2
(2890 3085);
DISPLAY 0.617021 (2890 3085);
PAINT ORANGE (2890 3085);
FORCEPROP 2 LASTPIN (2900 3025) $PN 9
J 2
(2890 3035);
DISPLAY 0.617021 (2890 3035);
PAINT ORANGE (2890 3035);
FORCEPROP 2 LASTPIN (2900 2975) $PN 11
J 2
(2890 2985);
DISPLAY 0.617021 (2890 2985);
PAINT ORANGE (2890 2985);
FORCEPROP 2 LASTPIN (2900 2925) $PN 13
J 2
(2890 2935);
DISPLAY 0.617021 (2890 2935);
PAINT ORANGE (2890 2935);
FORCEPROP 2 LASTPIN (2900 2875) $PN 15
J 2
(2890 2885);
DISPLAY 0.617021 (2890 2885);
PAINT ORANGE (2890 2885);
FORCEPROP 2 LASTPIN (2900 2825) $PN 17
J 2
(2890 2835);
DISPLAY 0.617021 (2890 2835);
PAINT ORANGE (2890 2835);
FORCEPROP 2 LASTPIN (2900 2775) $PN 20
J 2
(2890 2785);
DISPLAY 0.617021 (2890 2785);
PAINT ORANGE (2890 2785);
FORCEPROP 2 LASTPIN (2900 2725) $PN 22
J 2
(2890 2735);
DISPLAY 0.617021 (2890 2735);
PAINT ORANGE (2890 2735);
FORCEPROP 2 LASTPIN (2900 2675) $PN 24
J 2
(2890 2685);
DISPLAY 0.617021 (2890 2685);
PAINT ORANGE (2890 2685);
FORCEPROP 2 LASTPIN (2900 2625) $PN 26
J 2
(2890 2635);
DISPLAY 0.617021 (2890 2635);
PAINT ORANGE (2890 2635);
FORCEPROP 2 LASTPIN (2900 2575) $PN 28
J 2
(2890 2585);
DISPLAY 0.617021 (2890 2585);
PAINT ORANGE (2890 2585);
FORCEPROP 2 LASTPIN (2900 2525) $PN 31
J 2
(2890 2535);
DISPLAY 0.617021 (2890 2535);
PAINT ORANGE (2890 2535);
FORCEPROP 2 LASTPIN (2900 2475) $PN 33
J 2
(2890 2485);
DISPLAY 0.617021 (2890 2485);
PAINT ORANGE (2890 2485);
FORCEPROP 2 LASTPIN (2900 2425) $PN 35
J 2
(2890 2435);
DISPLAY 0.617021 (2890 2435);
PAINT ORANGE (2890 2435);
FORCEPROP 2 LASTPIN (2900 2375) $PN 37
J 2
(2890 2385);
DISPLAY 0.617021 (2890 2385);
PAINT ORANGE (2890 2385);
FORCEPROP 2 LASTPIN (2900 2325) $PN 39
J 2
(2890 2335);
DISPLAY 0.617021 (2890 2335);
PAINT ORANGE (2890 2335);
FORCEPROP 2 LASTPIN (2900 2275) $PN 42
J 2
(2890 2285);
DISPLAY 0.617021 (2890 2285);
PAINT ORANGE (2890 2285);
FORCEPROP 2 LASTPIN (2900 2225) $PN 44
J 2
(2890 2235);
DISPLAY 0.617021 (2890 2235);
PAINT ORANGE (2890 2235);
FORCEPROP 2 LASTPIN (2900 2175) $PN 46
J 2
(2890 2185);
DISPLAY 0.617021 (2890 2185);
PAINT ORANGE (2890 2185);
FORCEPROP 2 LASTPIN (2900 2125) $PN 48
J 2
(2890 2135);
DISPLAY 0.617021 (2890 2135);
PAINT ORANGE (2890 2135);
FORCEPROP 2 LASTPIN (2900 2075) $PN 50
J 2
(2890 2085);
DISPLAY 0.617021 (2890 2085);
PAINT ORANGE (2890 2085);
FORCEPROP 2 LASTPIN (2900 2025) $PN 53
J 2
(2890 2035);
DISPLAY 0.617021 (2890 2035);
PAINT ORANGE (2890 2035);
FORCEPROP 2 LASTPIN (2900 1975) $PN 55
J 2
(2890 1985);
DISPLAY 0.617021 (2890 1985);
PAINT ORANGE (2890 1985);
FORCEPROP 2 LASTPIN (2900 1875) $PN 94
J 2
(2890 1885);
DISPLAY 0.617021 (2890 1885);
PAINT ORANGE (2890 1885);
FORCEPROP 2 LASTPIN (2900 1825) $PN 96
J 2
(2890 1835);
DISPLAY 0.617021 (2890 1835);
PAINT ORANGE (2890 1835);
FORCEPROP 2 LASTPIN (2900 1775) $PN 98
J 2
(2890 1785);
DISPLAY 0.617021 (2890 1785);
PAINT ORANGE (2890 1785);
FORCEPROP 2 LASTPIN (2900 1625) $PN 105
J 2
(2890 1635);
DISPLAY 0.617021 (2890 1635);
PAINT ORANGE (2890 1635);
FORCEPROP 2 LASTPIN (2900 1575) $PN 107
J 2
(2890 1585);
DISPLAY 0.617021 (2890 1585);
PAINT ORANGE (2890 1585);
FORCEPROP 2 LASTPIN (2900 1525) $PN 109
J 2
(2890 1535);
DISPLAY 0.617021 (2890 1535);
PAINT ORANGE (2890 1535);
FORCEPROP 2 LASTPIN (2900 1475) $PN 112
J 2
(2890 1485);
DISPLAY 0.617021 (2890 1485);
PAINT ORANGE (2890 1485);
FORCEPROP 2 LASTPIN (2900 1425) $PN 114
J 2
(2890 1435);
DISPLAY 0.617021 (2890 1435);
PAINT ORANGE (2890 1435);
FORCEPROP 2 LASTPIN (2900 1375) $PN 116
J 2
(2890 1385);
DISPLAY 0.617021 (2890 1385);
PAINT ORANGE (2890 1385);
FORCEPROP 2 LASTPIN (2900 1325) $PN 118
J 2
(2890 1335);
DISPLAY 0.617021 (2890 1335);
PAINT ORANGE (2890 1335);
FORCEPROP 2 LASTPIN (2900 1275) $PN 120
J 2
(2890 1285);
DISPLAY 0.617021 (2890 1285);
PAINT ORANGE (2890 1285);
FORCEPROP 2 LASTPIN (2900 1225) $PN 123
J 2
(2890 1235);
DISPLAY 0.617021 (2890 1235);
PAINT ORANGE (2890 1235);
FORCEPROP 2 LASTPIN (2900 1175) $PN 125
J 2
(2890 1185);
DISPLAY 0.617021 (2890 1185);
PAINT ORANGE (2890 1185);
FORCEPROP 2 LASTPIN (2900 1125) $PN 127
J 2
(2890 1135);
DISPLAY 0.617021 (2890 1135);
PAINT ORANGE (2890 1135);
FORCEPROP 2 LASTPIN (2900 1075) $PN 129
J 2
(2890 1085);
DISPLAY 0.617021 (2890 1085);
PAINT ORANGE (2890 1085);
FORCEPROP 2 LASTPIN (2900 1025) $PN 131
J 2
(2890 1035);
DISPLAY 0.617021 (2890 1035);
PAINT ORANGE (2890 1035);
FORCEPROP 2 LASTPIN (2900 975) $PN 134
J 2
(2890 985);
DISPLAY 0.617021 (2890 985);
PAINT ORANGE (2890 985);
FORCEPROP 2 LASTPIN (2900 925) $PN 136
J 2
(2890 935);
DISPLAY 0.617021 (2890 935);
PAINT ORANGE (2890 935);
FORCEPROP 2 LASTPIN (2900 875) $PN 138
J 2
(2890 885);
DISPLAY 0.617021 (2890 885);
PAINT ORANGE (2890 885);
FORCEPROP 2 LASTPIN (3900 3175) $PN 147
J 0
(3910 3185);
DISPLAY 0.617021 (3910 3185);
PAINT ORANGE (3910 3185);
FORCEPROP 2 LASTPIN (3900 3125) $PN 149
J 0
(3910 3135);
DISPLAY 0.617021 (3910 3135);
PAINT ORANGE (3910 3135);
FORCEPROP 2 LASTPIN (3900 3075) $PN 151
J 0
(3910 3085);
DISPLAY 0.617021 (3910 3085);
PAINT ORANGE (3910 3085);
FORCEPROP 2 LASTPIN (3900 3025) $PN 154
J 0
(3910 3035);
DISPLAY 0.617021 (3910 3035);
PAINT ORANGE (3910 3035);
FORCEPROP 2 LASTPIN (3900 2975) $PN 156
J 0
(3910 2985);
DISPLAY 0.617021 (3910 2985);
PAINT ORANGE (3910 2985);
FORCEPROP 2 LASTPIN (3900 2925) $PN 158
J 0
(3910 2935);
DISPLAY 0.617021 (3910 2935);
PAINT ORANGE (3910 2935);
FORCEPROP 2 LASTPIN (3900 2825) $PN 162
J 0
(3910 2835);
DISPLAY 0.617021 (3910 2835);
PAINT ORANGE (3910 2835);
FORCEPROP 2 LASTPIN (3900 2775) $PN 165
J 0
(3910 2785);
DISPLAY 0.617021 (3910 2785);
PAINT ORANGE (3910 2785);
FORCEPROP 2 LASTPIN (3900 2725) $PN 167
J 0
(3910 2735);
DISPLAY 0.617021 (3910 2735);
PAINT ORANGE (3910 2735);
FORCEPROP 2 LASTPIN (3900 2675) $PN 169
J 0
(3910 2685);
DISPLAY 0.617021 (3910 2685);
PAINT ORANGE (3910 2685);
FORCEPROP 2 LASTPIN (3900 2625) $PN 171
J 0
(3910 2635);
DISPLAY 0.617021 (3910 2635);
PAINT ORANGE (3910 2635);
FORCEPROP 2 LASTPIN (3900 2575) $PN 173
J 0
(3910 2585);
DISPLAY 0.617021 (3910 2585);
PAINT ORANGE (3910 2585);
FORCEPROP 2 LASTPIN (3900 2525) $PN 176
J 0
(3910 2535);
DISPLAY 0.617021 (3910 2535);
PAINT ORANGE (3910 2535);
FORCEPROP 2 LASTPIN (3900 2475) $PN 178
J 0
(3910 2485);
DISPLAY 0.617021 (3910 2485);
PAINT ORANGE (3910 2485);
FORCEPROP 2 LASTPIN (3900 2425) $PN 180
J 0
(3910 2435);
DISPLAY 0.617021 (3910 2435);
PAINT ORANGE (3910 2435);
FORCEPROP 2 LASTPIN (3900 2375) $PN 182
J 0
(3910 2385);
DISPLAY 0.617021 (3910 2385);
PAINT ORANGE (3910 2385);
FORCEPROP 2 LASTPIN (3900 2325) $PN 184
J 0
(3910 2335);
DISPLAY 0.617021 (3910 2335);
PAINT ORANGE (3910 2335);
FORCEPROP 2 LASTPIN (3900 2275) $PN 187
J 0
(3910 2285);
DISPLAY 0.617021 (3910 2285);
PAINT ORANGE (3910 2285);
FORCEPROP 2 LASTPIN (3900 2225) $PN 189
J 0
(3910 2235);
DISPLAY 0.617021 (3910 2235);
PAINT ORANGE (3910 2235);
FORCEPROP 2 LASTPIN (3900 2175) $PN 191
J 0
(3910 2185);
DISPLAY 0.617021 (3910 2185);
PAINT ORANGE (3910 2185);
FORCEPROP 2 LASTPIN (3900 2125) $PN 193
J 0
(3910 2135);
DISPLAY 0.617021 (3910 2135);
PAINT ORANGE (3910 2135);
FORCEPROP 2 LASTPIN (3900 2075) $PN 195
J 0
(3910 2085);
DISPLAY 0.617021 (3910 2085);
PAINT ORANGE (3910 2085);
FORCEPROP 2 LASTPIN (3900 2025) $PN 198
J 0
(3910 2035);
DISPLAY 0.617021 (3910 2035);
PAINT ORANGE (3910 2035);
FORCEPROP 2 LASTPIN (3900 1975) $PN 200
J 0
(3910 1985);
DISPLAY 0.617021 (3910 1985);
PAINT ORANGE (3910 1985);
FORCEPROP 2 LASTPIN (3900 1925) $PN 202
J 0
(3910 1935);
DISPLAY 0.617021 (3910 1935);
PAINT ORANGE (3910 1935);
FORCEPROP 2 LASTPIN (3900 1875) $PN 239
J 0
(3910 1885);
DISPLAY 0.617021 (3910 1885);
PAINT ORANGE (3910 1885);
FORCEPROP 2 LASTPIN (3900 1825) $PN 241
J 0
(3910 1835);
DISPLAY 0.617021 (3910 1835);
PAINT ORANGE (3910 1835);
FORCEPROP 2 LASTPIN (3900 1775) $PN 243
J 0
(3910 1785);
DISPLAY 0.617021 (3910 1785);
PAINT ORANGE (3910 1785);
FORCEPROP 2 LASTPIN (3900 1725) $PN 246
J 0
(3910 1735);
DISPLAY 0.617021 (3910 1735);
PAINT ORANGE (3910 1735);
FORCEPROP 2 LASTPIN (3900 1675) $PN 248
J 0
(3910 1685);
DISPLAY 0.617021 (3910 1685);
PAINT ORANGE (3910 1685);
FORCEPROP 2 LASTPIN (3900 1625) $PN 250
J 0
(3910 1635);
DISPLAY 0.617021 (3910 1635);
PAINT ORANGE (3910 1635);
FORCEPROP 2 LASTPIN (3900 1575) $PN 252
J 0
(3910 1585);
DISPLAY 0.617021 (3910 1585);
PAINT ORANGE (3910 1585);
FORCEPROP 2 LASTPIN (3900 1525) $PN 254
J 0
(3910 1535);
DISPLAY 0.617021 (3910 1535);
PAINT ORANGE (3910 1535);
FORCEPROP 2 LASTPIN (3900 1475) $PN 257
J 0
(3910 1485);
DISPLAY 0.617021 (3910 1485);
PAINT ORANGE (3910 1485);
FORCEPROP 2 LASTPIN (3900 1425) $PN 259
J 0
(3910 1435);
DISPLAY 0.617021 (3910 1435);
PAINT ORANGE (3910 1435);
FORCEPROP 2 LASTPIN (3900 1375) $PN 261
J 0
(3910 1385);
DISPLAY 0.617021 (3910 1385);
PAINT ORANGE (3910 1385);
FORCEPROP 2 LASTPIN (3900 1325) $PN 263
J 0
(3910 1335);
DISPLAY 0.617021 (3910 1335);
PAINT ORANGE (3910 1335);
FORCEPROP 2 LASTPIN (3900 1275) $PN 265
J 0
(3910 1285);
DISPLAY 0.617021 (3910 1285);
PAINT ORANGE (3910 1285);
FORCEPROP 2 LASTPIN (3900 1225) $PN 268
J 0
(3910 1235);
DISPLAY 0.617021 (3910 1235);
PAINT ORANGE (3910 1235);
FORCEPROP 2 LASTPIN (3900 1175) $PN 270
J 0
(3910 1185);
DISPLAY 0.617021 (3910 1185);
PAINT ORANGE (3910 1185);
FORCEPROP 2 LASTPIN (3900 1125) $PN 272
J 0
(3910 1135);
DISPLAY 0.617021 (3910 1135);
PAINT ORANGE (3910 1135);
FORCEPROP 2 LASTPIN (3900 1075) $PN 274
J 0
(3910 1085);
DISPLAY 0.617021 (3910 1085);
PAINT ORANGE (3910 1085);
FORCEPROP 2 LASTPIN (3900 1025) $PN 276
J 0
(3910 1035);
DISPLAY 0.617021 (3910 1035);
PAINT ORANGE (3910 1035);
FORCEPROP 2 LASTPIN (3900 975) $PN 279
J 0
(3910 985);
DISPLAY 0.617021 (3910 985);
PAINT ORANGE (3910 985);
FORCEPROP 2 LASTPIN (3900 925) $PN 281
J 0
(3910 935);
DISPLAY 0.617021 (3910 935);
PAINT ORANGE (3910 935);
FORCEPROP 2 LASTPIN (2900 1925) $PN 57
J 2
(2890 1935);
DISPLAY 0.617021 (2890 1935);
PAINT ORANGE (2890 1935);
FORCEPROP 2 LASTPIN (3900 2875) $PN 160
J 0
(3910 2885);
DISPLAY 0.617021 (3910 2885);
PAINT ORANGE (3910 2885);
FORCEPROP 2 LASTPIN (3900 875) $PN 283
J 0
(3910 885);
DISPLAY 0.617021 (3910 885);
PAINT ORANGE (3910 885);
FORCEPROP 2 LASTPIN (2900 1725) $PN 101
J 2
(2890 1735);
DISPLAY 0.617021 (2890 1735);
PAINT ORANGE (2890 1735);
FORCEPROP 1 LAST MATERIAL SCONN
J 0
(2950 3375);
DISPLAY 0.617021 (2950 3375);
PAINT SKYBLUE (2950 3375);
FORCEPROP 0 LAST BOM_SS NOPOP
J 0
(3141 3376);
DISPLAY 1.021277 (3141 3376);
PAINT BROWN (3141 3376);
DISPLAY BOTH (3141 3376);
FORCEPROP 2 LASTPIN (2900 1675) $PN 103
J 2
(2890 1685);
DISPLAY 0.617021 (2890 1685);
PAINT ORANGE (2890 1685);
FORCEPROP 1 LAST PACK_TYPE PIP
J 0
(2950 3475);
PAINT SKYBLUE (2950 3475);
DISPLAY INVISIBLE (2950 3475);
FORCEPROP 2 LAST BOM_COST MEM
J 0
(3400 2025);
PAINT ORANGE (3400 2025);
DISPLAY INVISIBLE (3400 2025);
FORCEPROP 2 LAST CDS_LIB mstr_sconn
J 0
(3400 2025);
PAINT ORANGE (3400 2025);
DISPLAY INVISIBLE (3400 2025);
FORCEPROP 2 LAST SEC_TYPE PIP
J 0
(2950 3475);
DISPLAY 1.021277 (2950 3475);
PAINT ORANGE (2950 3475);
DISPLAY INVISIBLE (2950 3475);
FORCEPROP 2 LAST SEC 3
J 0
(2950 3475);
DISPLAY 0.680851 (2950 3475);
PAINT MONO (2950 3475);
DISPLAY INVISIBLE (2950 3475);
FORCEPROP 2 LAST CDS_LOCATION J9M1
J 0
(2950 3425);
DISPLAY 0.617021 (2950 3425);
PAINT AQUA (2950 3425);
DISPLAY INVISIBLE (2950 3425);
FORCEPROP 1 LAST PATH I138
J 0
(3400 3375);
PAINT GREEN (3400 3375);
DISPLAY INVISIBLE (3400 3375);
FORCEPROP 2 LAST ROOM DDR4_CH_K
J 0
(3400 2025);
PAINT ORANGE (3400 2025);
DISPLAY INVISIBLE (3400 2025);
FORCEADD SCONN288_H44441003..1
(-850 2825);
FORCEPROP 1 LAST LOCATION J9M1
J 0
(-1300 4725);
DISPLAY 0.617021 (-1300 4725);
PAINT AQUA (-1300 4725);
FORCEPROP 1 LAST PART_NUMBER H44441-003
J 0
(-1300 825);
DISPLAY 0.617021 (-1300 825);
PAINT BLUE (-1300 825);
FORCEPROP 1 LAST MATERIAL SCONN
J 0
(-1300 4675);
DISPLAY 0.617021 (-1300 4675);
PAINT SKYBLUE (-1300 4675);
FORCEPROP 2 LASTPIN (-1350 1325) $PN 146
J 2
(-1360 1335);
DISPLAY 0.617021 (-1360 1335);
PAINT ORANGE (-1360 1335);
FORCEPROP 2 LASTPIN (-1350 1675) $PN 284
J 2
(-1360 1685);
DISPLAY 0.617021 (-1360 1685);
PAINT ORANGE (-1360 1685);
FORCEPROP 2 LASTPIN (-1350 1475) $PN 285
J 2
(-1360 1485);
DISPLAY 0.617021 (-1360 1485);
PAINT ORANGE (-1360 1485);
FORCEPROP 2 LASTPIN (-1350 1425) $PN 141
J 2
(-1360 1435);
DISPLAY 0.617021 (-1360 1435);
PAINT ORANGE (-1360 1435);
FORCEPROP 2 LASTPIN (-1350 1025) $PN 230
J 2
(-1360 1035);
DISPLAY 0.617021 (-1360 1035);
PAINT ORANGE (-1360 1035);
FORCEPROP 2 LASTPIN (-1350 1625) $PN 238
J 2
(-1360 1635);
DISPLAY 0.617021 (-1360 1635);
PAINT ORANGE (-1360 1635);
FORCEPROP 2 LASTPIN (-1350 1575) $PN 140
J 2
(-1360 1585);
DISPLAY 0.617021 (-1360 1585);
PAINT ORANGE (-1360 1585);
FORCEPROP 2 LASTPIN (-1350 1525) $PN 139
J 2
(-1360 1535);
DISPLAY 0.617021 (-1360 1535);
PAINT ORANGE (-1360 1535);
FORCEPROP 2 LASTPIN (-1350 2975) $PN 237
J 2
(-1360 2985);
DISPLAY 0.617021 (-1360 2985);
PAINT ORANGE (-1360 2985);
FORCEPROP 2 LASTPIN (-1350 2925) $PN 93
J 2
(-1360 2935);
DISPLAY 0.617021 (-1360 2935);
PAINT ORANGE (-1360 2935);
FORCEPROP 2 LASTPIN (-1350 2875) $PN 89
J 2
(-1360 2885);
DISPLAY 0.617021 (-1360 2885);
PAINT ORANGE (-1360 2885);
FORCEPROP 2 LASTPIN (-1350 2825) $PN 84
J 2
(-1360 2835);
DISPLAY 0.617021 (-1360 2835);
PAINT ORANGE (-1360 2835);
FORCEPROP 2 LASTPIN (-1350 1225) $PN 144
J 2
(-1360 1235);
DISPLAY 0.617021 (-1360 1235);
PAINT ORANGE (-1360 1235);
FORCEPROP 2 LASTPIN (-1350 1175) $PN 227
J 2
(-1360 1185);
DISPLAY 0.617021 (-1360 1185);
PAINT ORANGE (-1360 1185);
FORCEPROP 2 LASTPIN (-1350 1125) $PN 205
J 2
(-1360 1135);
DISPLAY 0.617021 (-1360 1135);
PAINT ORANGE (-1360 1135);
FORCEPROP 2 LASTPIN (-1350 1925) $PN 58
J 2
(-1360 1935);
DISPLAY 0.617021 (-1360 1935);
PAINT ORANGE (-1360 1935);
FORCEPROP 2 LASTPIN (-1350 1975) $PN 222
J 2
(-1360 1985);
DISPLAY 0.617021 (-1360 1985);
PAINT ORANGE (-1360 1985);
FORCEPROP 2 LASTPIN (-1350 2575) $PN 91
J 2
(-1360 2585);
DISPLAY 0.617021 (-1360 2585);
PAINT ORANGE (-1360 2585);
FORCEPROP 2 LASTPIN (-1350 2525) $PN 87
J 2
(-1360 2535);
DISPLAY 0.617021 (-1360 2535);
PAINT ORANGE (-1360 2535);
FORCEPROP 2 LASTPIN (-1350 1875) $PN 78
J 2
(-1360 1885);
DISPLAY 0.617021 (-1360 1885);
PAINT ORANGE (-1360 1885);
FORCEPROP 2 LASTPIN (-350 4475) $PN 280
J 0
(-340 4485);
DISPLAY 0.617021 (-340 4485);
PAINT ORANGE (-340 4485);
FORCEPROP 2 LASTPIN (-350 4425) $PN 135
J 0
(-340 4435);
DISPLAY 0.617021 (-340 4435);
PAINT ORANGE (-340 4435);
FORCEPROP 2 LASTPIN (-350 4375) $PN 273
J 0
(-340 4385);
DISPLAY 0.617021 (-340 4385);
PAINT ORANGE (-340 4385);
FORCEPROP 2 LASTPIN (-350 4325) $PN 128
J 0
(-340 4335);
DISPLAY 0.617021 (-340 4335);
PAINT ORANGE (-340 4335);
FORCEPROP 2 LASTPIN (-350 4275) $PN 282
J 0
(-340 4285);
DISPLAY 0.617021 (-340 4285);
PAINT ORANGE (-340 4285);
FORCEPROP 2 LASTPIN (-350 4225) $PN 137
J 0
(-340 4235);
DISPLAY 0.617021 (-340 4235);
PAINT ORANGE (-340 4235);
FORCEPROP 2 LASTPIN (-350 4175) $PN 275
J 0
(-340 4185);
DISPLAY 0.617021 (-340 4185);
PAINT ORANGE (-340 4185);
FORCEPROP 2 LASTPIN (-350 4125) $PN 130
J 0
(-340 4135);
DISPLAY 0.617021 (-340 4135);
PAINT ORANGE (-340 4135);
FORCEPROP 2 LASTPIN (-350 4075) $PN 269
J 0
(-340 4085);
DISPLAY 0.617021 (-340 4085);
PAINT ORANGE (-340 4085);
FORCEPROP 2 LASTPIN (-350 4025) $PN 124
J 0
(-340 4035);
DISPLAY 0.617021 (-340 4035);
PAINT ORANGE (-340 4035);
FORCEPROP 2 LASTPIN (-350 3975) $PN 262
J 0
(-340 3985);
DISPLAY 0.617021 (-340 3985);
PAINT ORANGE (-340 3985);
FORCEPROP 2 LASTPIN (-350 3925) $PN 117
J 0
(-340 3935);
DISPLAY 0.617021 (-340 3935);
PAINT ORANGE (-340 3935);
FORCEPROP 2 LASTPIN (-350 3875) $PN 271
J 0
(-340 3885);
DISPLAY 0.617021 (-340 3885);
PAINT ORANGE (-340 3885);
FORCEPROP 2 LASTPIN (-350 3825) $PN 126
J 0
(-340 3835);
DISPLAY 0.617021 (-340 3835);
PAINT ORANGE (-340 3835);
FORCEPROP 2 LASTPIN (-350 3775) $PN 264
J 0
(-340 3785);
DISPLAY 0.617021 (-340 3785);
PAINT ORANGE (-340 3785);
FORCEPROP 2 LASTPIN (-350 3725) $PN 119
J 0
(-340 3735);
DISPLAY 0.617021 (-340 3735);
PAINT ORANGE (-340 3735);
FORCEPROP 2 LASTPIN (-350 3675) $PN 258
J 0
(-340 3685);
DISPLAY 0.617021 (-340 3685);
PAINT ORANGE (-340 3685);
FORCEPROP 2 LASTPIN (-350 3625) $PN 113
J 0
(-340 3635);
DISPLAY 0.617021 (-340 3635);
PAINT ORANGE (-340 3635);
FORCEPROP 2 LASTPIN (-350 3575) $PN 251
J 0
(-340 3585);
DISPLAY 0.617021 (-340 3585);
PAINT ORANGE (-340 3585);
FORCEPROP 2 LASTPIN (-350 3525) $PN 106
J 0
(-340 3535);
DISPLAY 0.617021 (-340 3535);
PAINT ORANGE (-340 3535);
FORCEPROP 2 LASTPIN (-350 3475) $PN 260
J 0
(-340 3485);
DISPLAY 0.617021 (-340 3485);
PAINT ORANGE (-340 3485);
FORCEPROP 2 LASTPIN (-350 3425) $PN 115
J 0
(-340 3435);
DISPLAY 0.617021 (-340 3435);
PAINT ORANGE (-340 3435);
FORCEPROP 2 LASTPIN (-350 3375) $PN 253
J 0
(-340 3385);
DISPLAY 0.617021 (-340 3385);
PAINT ORANGE (-340 3385);
FORCEPROP 2 LASTPIN (-350 3325) $PN 108
J 0
(-340 3335);
DISPLAY 0.617021 (-340 3335);
PAINT ORANGE (-340 3335);
FORCEPROP 2 LASTPIN (-350 3275) $PN 247
J 0
(-340 3285);
DISPLAY 0.617021 (-340 3285);
PAINT ORANGE (-340 3285);
FORCEPROP 2 LASTPIN (-350 3225) $PN 102
J 0
(-340 3235);
DISPLAY 0.617021 (-340 3235);
PAINT ORANGE (-340 3235);
FORCEPROP 2 LASTPIN (-350 3175) $PN 240
J 0
(-340 3185);
DISPLAY 0.617021 (-340 3185);
PAINT ORANGE (-340 3185);
FORCEPROP 2 LASTPIN (-350 3125) $PN 95
J 0
(-340 3135);
DISPLAY 0.617021 (-340 3135);
PAINT ORANGE (-340 3135);
FORCEPROP 2 LASTPIN (-350 3075) $PN 249
J 0
(-340 3085);
DISPLAY 0.617021 (-340 3085);
PAINT ORANGE (-340 3085);
FORCEPROP 2 LASTPIN (-350 3025) $PN 104
J 0
(-340 3035);
DISPLAY 0.617021 (-340 3035);
PAINT ORANGE (-340 3035);
FORCEPROP 2 LASTPIN (-350 2975) $PN 242
J 0
(-340 2985);
DISPLAY 0.617021 (-340 2985);
PAINT ORANGE (-340 2985);
FORCEPROP 2 LASTPIN (-350 2925) $PN 97
J 0
(-340 2935);
DISPLAY 0.617021 (-340 2935);
PAINT ORANGE (-340 2935);
FORCEPROP 2 LASTPIN (-350 2875) $PN 188
J 0
(-340 2885);
DISPLAY 0.617021 (-340 2885);
PAINT ORANGE (-340 2885);
FORCEPROP 2 LASTPIN (-350 2825) $PN 43
J 0
(-340 2835);
DISPLAY 0.617021 (-340 2835);
PAINT ORANGE (-340 2835);
FORCEPROP 2 LASTPIN (-350 2775) $PN 181
J 0
(-340 2785);
DISPLAY 0.617021 (-340 2785);
PAINT ORANGE (-340 2785);
FORCEPROP 2 LASTPIN (-350 2725) $PN 36
J 0
(-340 2735);
DISPLAY 0.617021 (-340 2735);
PAINT ORANGE (-340 2735);
FORCEPROP 2 LASTPIN (-350 2675) $PN 190
J 0
(-340 2685);
DISPLAY 0.617021 (-340 2685);
PAINT ORANGE (-340 2685);
FORCEPROP 2 LASTPIN (-350 2625) $PN 45
J 0
(-340 2635);
DISPLAY 0.617021 (-340 2635);
PAINT ORANGE (-340 2635);
FORCEPROP 2 LASTPIN (-350 2575) $PN 183
J 0
(-340 2585);
DISPLAY 0.617021 (-340 2585);
PAINT ORANGE (-340 2585);
FORCEPROP 2 LASTPIN (-350 2525) $PN 38
J 0
(-340 2535);
DISPLAY 0.617021 (-340 2535);
PAINT ORANGE (-340 2535);
FORCEPROP 2 LASTPIN (-350 2475) $PN 177
J 0
(-340 2485);
DISPLAY 0.617021 (-340 2485);
PAINT ORANGE (-340 2485);
FORCEPROP 2 LASTPIN (-350 2425) $PN 32
J 0
(-340 2435);
DISPLAY 0.617021 (-340 2435);
PAINT ORANGE (-340 2435);
FORCEPROP 2 LASTPIN (-350 2375) $PN 170
J 0
(-340 2385);
DISPLAY 0.617021 (-340 2385);
PAINT ORANGE (-340 2385);
FORCEPROP 2 LASTPIN (-350 2325) $PN 25
J 0
(-340 2335);
DISPLAY 0.617021 (-340 2335);
PAINT ORANGE (-340 2335);
FORCEPROP 2 LASTPIN (-350 2275) $PN 179
J 0
(-340 2285);
DISPLAY 0.617021 (-340 2285);
PAINT ORANGE (-340 2285);
FORCEPROP 2 LASTPIN (-350 2225) $PN 34
J 0
(-340 2235);
DISPLAY 0.617021 (-340 2235);
PAINT ORANGE (-340 2235);
FORCEPROP 2 LASTPIN (-350 2175) $PN 172
J 0
(-340 2185);
DISPLAY 0.617021 (-340 2185);
PAINT ORANGE (-340 2185);
FORCEPROP 2 LASTPIN (-350 2125) $PN 27
J 0
(-340 2135);
DISPLAY 0.617021 (-340 2135);
PAINT ORANGE (-340 2135);
FORCEPROP 2 LASTPIN (-350 2075) $PN 166
J 0
(-340 2085);
DISPLAY 0.617021 (-340 2085);
PAINT ORANGE (-340 2085);
FORCEPROP 2 LASTPIN (-350 2025) $PN 21
J 0
(-340 2035);
DISPLAY 0.617021 (-340 2035);
PAINT ORANGE (-340 2035);
FORCEPROP 2 LASTPIN (-350 1975) $PN 159
J 0
(-340 1985);
DISPLAY 0.617021 (-340 1985);
PAINT ORANGE (-340 1985);
FORCEPROP 2 LASTPIN (-350 1925) $PN 14
J 0
(-340 1935);
DISPLAY 0.617021 (-340 1935);
PAINT ORANGE (-340 1935);
FORCEPROP 2 LASTPIN (-350 1875) $PN 168
J 0
(-340 1885);
DISPLAY 0.617021 (-340 1885);
PAINT ORANGE (-340 1885);
FORCEPROP 2 LASTPIN (-350 1825) $PN 23
J 0
(-340 1835);
DISPLAY 0.617021 (-340 1835);
PAINT ORANGE (-340 1835);
FORCEPROP 2 LASTPIN (-350 1775) $PN 161
J 0
(-340 1785);
DISPLAY 0.617021 (-340 1785);
PAINT ORANGE (-340 1785);
FORCEPROP 2 LASTPIN (-350 1725) $PN 16
J 0
(-340 1735);
DISPLAY 0.617021 (-340 1735);
PAINT ORANGE (-340 1735);
FORCEPROP 2 LASTPIN (-350 1675) $PN 155
J 0
(-340 1685);
DISPLAY 0.617021 (-340 1685);
PAINT ORANGE (-340 1685);
FORCEPROP 2 LASTPIN (-350 1625) $PN 10
J 0
(-340 1635);
DISPLAY 0.617021 (-340 1635);
PAINT ORANGE (-340 1635);
FORCEPROP 2 LASTPIN (-350 1575) $PN 148
J 0
(-340 1585);
DISPLAY 0.617021 (-340 1585);
PAINT ORANGE (-340 1585);
FORCEPROP 2 LASTPIN (-350 1525) $PN 3
J 0
(-340 1535);
DISPLAY 0.617021 (-340 1535);
PAINT ORANGE (-340 1535);
FORCEPROP 2 LASTPIN (-350 1475) $PN 157
J 0
(-340 1485);
DISPLAY 0.617021 (-340 1485);
PAINT ORANGE (-340 1485);
FORCEPROP 2 LASTPIN (-350 1425) $PN 12
J 0
(-340 1435);
DISPLAY 0.617021 (-340 1435);
PAINT ORANGE (-340 1435);
FORCEPROP 2 LASTPIN (-350 1375) $PN 150
J 0
(-340 1385);
DISPLAY 0.617021 (-340 1385);
PAINT ORANGE (-340 1385);
FORCEPROP 2 LASTPIN (-350 1325) $PN 5
J 0
(-340 1335);
DISPLAY 0.617021 (-340 1335);
PAINT ORANGE (-340 1335);
FORCEPROP 2 LASTPIN (-1350 2725) $PN 203
J 2
(-1360 2735);
DISPLAY 0.617021 (-1360 2735);
PAINT ORANGE (-1360 2735);
FORCEPROP 2 LASTPIN (-1350 2675) $PN 60
J 2
(-1360 2685);
DISPLAY 0.617021 (-1360 2685);
PAINT ORANGE (-1360 2685);
FORCEPROP 2 LASTPIN (-1350 3275) $PN 218
J 2
(-1360 3285);
DISPLAY 0.617021 (-1360 3285);
PAINT ORANGE (-1360 3285);
FORCEPROP 2 LASTPIN (-1350 3225) $PN 219
J 2
(-1360 3235);
DISPLAY 0.617021 (-1360 3235);
PAINT ORANGE (-1360 3235);
FORCEPROP 2 LASTPIN (-1350 3175) $PN 74
J 2
(-1360 3185);
DISPLAY 0.617021 (-1360 3185);
PAINT ORANGE (-1360 3185);
FORCEPROP 2 LASTPIN (-1350 3125) $PN 75
J 2
(-1360 3135);
DISPLAY 0.617021 (-1360 3135);
PAINT ORANGE (-1360 3135);
FORCEPROP 2 LASTPIN (-1350 2425) $PN 199
J 2
(-1360 2435);
DISPLAY 0.617021 (-1360 2435);
PAINT ORANGE (-1360 2435);
FORCEPROP 2 LASTPIN (-1350 2375) $PN 54
J 2
(-1360 2385);
DISPLAY 0.617021 (-1360 2385);
PAINT ORANGE (-1360 2385);
FORCEPROP 2 LASTPIN (-1350 2325) $PN 192
J 2
(-1360 2335);
DISPLAY 0.617021 (-1360 2335);
PAINT ORANGE (-1360 2335);
FORCEPROP 2 LASTPIN (-1350 2275) $PN 47
J 2
(-1360 2285);
DISPLAY 0.617021 (-1360 2285);
PAINT ORANGE (-1360 2285);
FORCEPROP 2 LASTPIN (-1350 2225) $PN 201
J 2
(-1360 2235);
DISPLAY 0.617021 (-1360 2235);
PAINT ORANGE (-1360 2235);
FORCEPROP 2 LASTPIN (-1350 2175) $PN 56
J 2
(-1360 2185);
DISPLAY 0.617021 (-1360 2185);
PAINT ORANGE (-1360 2185);
FORCEPROP 2 LASTPIN (-1350 2125) $PN 194
J 2
(-1360 2135);
DISPLAY 0.617021 (-1360 2135);
PAINT ORANGE (-1360 2135);
FORCEPROP 2 LASTPIN (-1350 2075) $PN 49
J 2
(-1360 2085);
DISPLAY 0.617021 (-1360 2085);
PAINT ORANGE (-1360 2085);
FORCEPROP 2 LASTPIN (-1350 3025) $PN 235
J 2
(-1360 3035);
DISPLAY 0.617021 (-1360 3035);
PAINT ORANGE (-1360 3035);
FORCEPROP 2 LASTPIN (-1350 3425) $PN 207
J 2
(-1360 3435);
DISPLAY 0.617021 (-1360 3435);
PAINT ORANGE (-1360 3435);
FORCEPROP 2 LASTPIN (-1350 3375) $PN 63
J 2
(-1360 3385);
DISPLAY 0.617021 (-1360 3385);
PAINT ORANGE (-1360 3385);
FORCEPROP 2 LASTPIN (-1350 3525) $PN 224
J 2
(-1360 3535);
DISPLAY 0.617021 (-1360 3535);
PAINT ORANGE (-1360 3535);
FORCEPROP 2 LASTPIN (-1350 3475) $PN 81
J 2
(-1360 3485);
DISPLAY 0.617021 (-1360 3485);
PAINT ORANGE (-1360 3485);
FORCEPROP 2 LASTPIN (-1350 1825) $PN 208
J 2
(-1360 1835);
DISPLAY 0.617021 (-1360 1835);
PAINT ORANGE (-1360 1835);
FORCEPROP 2 LASTPIN (-1350 1775) $PN 62
J 2
(-1360 1785);
DISPLAY 0.617021 (-1360 1785);
PAINT ORANGE (-1360 1785);
FORCEPROP 2 LASTPIN (-1350 4475) $PN 234
J 2
(-1360 4485);
DISPLAY 0.617021 (-1360 4485);
PAINT ORANGE (-1360 4485);
FORCEPROP 2 LASTPIN (-1350 4425) $PN 82
J 2
(-1360 4435);
DISPLAY 0.617021 (-1360 4435);
PAINT ORANGE (-1360 4435);
FORCEPROP 2 LASTPIN (-1350 4375) $PN 86
J 2
(-1360 4385);
DISPLAY 0.617021 (-1360 4385);
PAINT ORANGE (-1360 4385);
FORCEPROP 2 LASTPIN (-1350 4325) $PN 228
J 2
(-1360 4335);
DISPLAY 0.617021 (-1360 4335);
PAINT ORANGE (-1360 4335);
FORCEPROP 2 LASTPIN (-1350 4275) $PN 232
J 2
(-1360 4285);
DISPLAY 0.617021 (-1360 4285);
PAINT ORANGE (-1360 4285);
FORCEPROP 2 LASTPIN (-1350 4225) $PN 65
J 2
(-1360 4235);
DISPLAY 0.617021 (-1360 4235);
PAINT ORANGE (-1360 4235);
FORCEPROP 2 LASTPIN (-1350 4175) $PN 210
J 2
(-1360 4185);
DISPLAY 0.617021 (-1360 4185);
PAINT ORANGE (-1360 4185);
FORCEPROP 2 LASTPIN (-1350 4125) $PN 225
J 2
(-1360 4135);
DISPLAY 0.617021 (-1360 4135);
PAINT ORANGE (-1360 4135);
FORCEPROP 2 LASTPIN (-1350 4075) $PN 66
J 2
(-1360 4085);
DISPLAY 0.617021 (-1360 4085);
PAINT ORANGE (-1360 4085);
FORCEPROP 2 LASTPIN (-1350 4025) $PN 68
J 2
(-1360 4035);
DISPLAY 0.617021 (-1360 4035);
PAINT ORANGE (-1360 4035);
FORCEPROP 2 LASTPIN (-1350 3975) $PN 211
J 2
(-1360 3985);
DISPLAY 0.617021 (-1360 3985);
PAINT ORANGE (-1360 3985);
FORCEPROP 2 LASTPIN (-1350 3925) $PN 69
J 2
(-1360 3935);
DISPLAY 0.617021 (-1360 3935);
PAINT ORANGE (-1360 3935);
FORCEPROP 2 LASTPIN (-1350 3875) $PN 213
J 2
(-1360 3885);
DISPLAY 0.617021 (-1360 3885);
PAINT ORANGE (-1360 3885);
FORCEPROP 2 LASTPIN (-1350 3825) $PN 214
J 2
(-1360 3835);
DISPLAY 0.617021 (-1360 3835);
PAINT ORANGE (-1360 3835);
FORCEPROP 2 LASTPIN (-1350 3775) $PN 71
J 2
(-1360 3785);
DISPLAY 0.617021 (-1360 3785);
PAINT ORANGE (-1360 3785);
FORCEPROP 2 LASTPIN (-1350 3725) $PN 216
J 2
(-1360 3735);
DISPLAY 0.617021 (-1360 3735);
PAINT ORANGE (-1360 3735);
FORCEPROP 2 LASTPIN (-1350 3625) $PN 79
J 2
(-1360 3635);
DISPLAY 0.617021 (-1360 3635);
PAINT ORANGE (-1360 3635);
FORCEPROP 0 LAST BOM_SS NOPOP
J 0
(-659 4651);
DISPLAY 1.021277 (-659 4651);
PAINT BROWN (-659 4651);
DISPLAY BOTH (-659 4651);
FORCEPROP 2 LASTPIN (-1350 3675) $PN 72
J 2
(-1360 3685);
DISPLAY 0.617021 (-1360 3685);
PAINT ORANGE (-1360 3685);
FORCEPROP 1 LAST PACK_TYPE PIP
J 0
(-1300 4775);
PAINT SKYBLUE (-1300 4775);
DISPLAY INVISIBLE (-1300 4775);
FORCEPROP 2 LAST BOM_COST MEM
J 0
(-850 2825);
PAINT ORANGE (-850 2825);
DISPLAY INVISIBLE (-850 2825);
FORCEPROP 2 LAST CDS_LIB mstr_sconn
J 0
(-850 2825);
PAINT ORANGE (-850 2825);
DISPLAY INVISIBLE (-850 2825);
FORCEPROP 2 LAST SEC_TYPE PIP
J 0
(-1300 4775);
DISPLAY 1.021277 (-1300 4775);
PAINT ORANGE (-1300 4775);
DISPLAY INVISIBLE (-1300 4775);
FORCEPROP 2 LAST SEC 1
J 0
(-1300 4775);
DISPLAY 0.680851 (-1300 4775);
PAINT MONO (-1300 4775);
DISPLAY INVISIBLE (-1300 4775);
FORCEPROP 2 LAST CDS_LOCATION J9M1
J 0
(-1300 4725);
DISPLAY 0.617021 (-1300 4725);
PAINT AQUA (-1300 4725);
DISPLAY INVISIBLE (-1300 4725);
FORCEPROP 1 LAST PATH I14
J 0
(-850 4675);
PAINT GREEN (-850 4675);
DISPLAY INVISIBLE (-850 4675);
FORCEPROP 2 LAST ROOM DDR4_CH_K
J 0
(-850 2825);
PAINT ORANGE (-850 2825);
DISPLAY INVISIBLE (-850 2825);
FORCEADD TAP..6
R 2
(2300 3125);
FORCEPROP 3 LASTPIN (2250 3125) SIG_NAME M_K_DQS_DP<0>
J 0
(2260 3135);
DISPLAY 0.659574 (2260 3135);
PAINT MONO (2260 3135);
DISPLAY INVISIBLE (2260 3135);
FORCEPROP 1 LASTPIN (2250 3125) BN 0
J 2
(2300 3135);
DISPLAY 0.617021 (2300 3135);
PAINT PINK (2300 3135);
FORCEPROP 2 LAST CDS_LIB mstr_standard
J 0
(2300 3125);
DISPLAY 0.787234 (2300 3125);
PAINT MONO (2300 3125);
DISPLAY INVISIBLE (2300 3125);
FORCEPROP 1 LAST BODY_TYPE PLUMBING
J 2
(2300 3075);
DISPLAY 1.234043 (2300 3075);
PAINT GREEN (2300 3075);
DISPLAY INVISIBLE (2300 3075);
FORCEPROP 1 LAST HDL_TAP TRUE
J 2
(1975 3000);
DISPLAY 1.234043 (1975 3000);
PAINT GREEN (1975 3000);
DISPLAY INVISIBLE (1975 3000);
FORCEPROP 1 LAST PATH I142
J 2
(2302 3125);
DISPLAY 0.872340 (2302 3125);
PAINT GREEN (2302 3125);
DISPLAY INVISIBLE (2302 3125);
FORCEADD TAP..6
R 2
(2500 3075);
FORCEPROP 3 LASTPIN (2450 3075) SIG_NAME M_K_DQS_DN<0>
J 0
(2460 3085);
DISPLAY 0.659574 (2460 3085);
PAINT MONO (2460 3085);
DISPLAY INVISIBLE (2460 3085);
FORCEPROP 1 LASTPIN (2450 3075) BN 0
J 2
(2500 3085);
DISPLAY 0.617021 (2500 3085);
PAINT PINK (2500 3085);
FORCEPROP 2 LAST CDS_LIB mstr_standard
J 0
(2500 3075);
DISPLAY 0.787234 (2500 3075);
PAINT MONO (2500 3075);
DISPLAY INVISIBLE (2500 3075);
FORCEPROP 1 LAST BODY_TYPE PLUMBING
J 2
(2500 3025);
DISPLAY 1.234043 (2500 3025);
PAINT GREEN (2500 3025);
DISPLAY INVISIBLE (2500 3025);
FORCEPROP 1 LAST HDL_TAP TRUE
J 2
(2175 2950);
DISPLAY 1.234043 (2175 2950);
PAINT GREEN (2175 2950);
DISPLAY INVISIBLE (2175 2950);
FORCEPROP 1 LAST PATH I143
J 2
(2502 3075);
DISPLAY 0.872340 (2502 3075);
PAINT GREEN (2502 3075);
DISPLAY INVISIBLE (2502 3075);
FORCEADD TAP..6
R 2
(2500 3175);
FORCEPROP 3 LASTPIN (2450 3175) SIG_NAME M_K_DQS_DN<1>
J 0
(2460 3185);
DISPLAY 0.659574 (2460 3185);
PAINT MONO (2460 3185);
DISPLAY INVISIBLE (2460 3185);
FORCEPROP 1 LASTPIN (2450 3175) BN 1
J 2
(2500 3185);
DISPLAY 0.617021 (2500 3185);
PAINT PINK (2500 3185);
FORCEPROP 2 LAST CDS_LIB mstr_standard
J 0
(2500 3175);
DISPLAY 0.787234 (2500 3175);
PAINT MONO (2500 3175);
DISPLAY INVISIBLE (2500 3175);
FORCEPROP 1 LAST BODY_TYPE PLUMBING
J 2
(2500 3125);
DISPLAY 1.234043 (2500 3125);
PAINT GREEN (2500 3125);
DISPLAY INVISIBLE (2500 3125);
FORCEPROP 1 LAST HDL_TAP TRUE
J 2
(2175 3050);
DISPLAY 1.234043 (2175 3050);
PAINT GREEN (2175 3050);
DISPLAY INVISIBLE (2175 3050);
FORCEPROP 1 LAST PATH I144
J 2
(2502 3175);
DISPLAY 0.872340 (2502 3175);
PAINT GREEN (2502 3175);
DISPLAY INVISIBLE (2502 3175);
FORCEADD TAP..6
R 2
(2300 3325);
FORCEPROP 3 LASTPIN (2250 3325) SIG_NAME M_K_DQS_DP<2>
J 0
(2260 3335);
DISPLAY 0.659574 (2260 3335);
PAINT MONO (2260 3335);
DISPLAY INVISIBLE (2260 3335);
FORCEPROP 1 LASTPIN (2250 3325) BN 2
J 2
(2300 3335);
DISPLAY 0.617021 (2300 3335);
PAINT PINK (2300 3335);
FORCEPROP 2 LAST CDS_LIB mstr_standard
J 0
(2300 3325);
DISPLAY 0.787234 (2300 3325);
PAINT MONO (2300 3325);
DISPLAY INVISIBLE (2300 3325);
FORCEPROP 1 LAST BODY_TYPE PLUMBING
J 2
(2300 3275);
DISPLAY 1.234043 (2300 3275);
PAINT GREEN (2300 3275);
DISPLAY INVISIBLE (2300 3275);
FORCEPROP 1 LAST HDL_TAP TRUE
J 2
(1975 3200);
DISPLAY 1.234043 (1975 3200);
PAINT GREEN (1975 3200);
DISPLAY INVISIBLE (1975 3200);
FORCEPROP 1 LAST PATH I145
J 2
(2302 3325);
DISPLAY 0.872340 (2302 3325);
PAINT GREEN (2302 3325);
DISPLAY INVISIBLE (2302 3325);
FORCEADD TAP..6
R 2
(2300 3225);
FORCEPROP 3 LASTPIN (2250 3225) SIG_NAME M_K_DQS_DP<1>
J 0
(2260 3235);
DISPLAY 0.659574 (2260 3235);
PAINT MONO (2260 3235);
DISPLAY INVISIBLE (2260 3235);
FORCEPROP 1 LASTPIN (2250 3225) BN 1
J 2
(2300 3235);
DISPLAY 0.617021 (2300 3235);
PAINT PINK (2300 3235);
FORCEPROP 2 LAST CDS_LIB mstr_standard
J 0
(2300 3225);
DISPLAY 0.787234 (2300 3225);
PAINT MONO (2300 3225);
DISPLAY INVISIBLE (2300 3225);
FORCEPROP 1 LAST BODY_TYPE PLUMBING
J 2
(2300 3175);
DISPLAY 1.234043 (2300 3175);
PAINT GREEN (2300 3175);
DISPLAY INVISIBLE (2300 3175);
FORCEPROP 1 LAST HDL_TAP TRUE
J 2
(1975 3100);
DISPLAY 1.234043 (1975 3100);
PAINT GREEN (1975 3100);
DISPLAY INVISIBLE (1975 3100);
FORCEPROP 1 LAST PATH I146
J 2
(2302 3225);
DISPLAY 0.872340 (2302 3225);
PAINT GREEN (2302 3225);
DISPLAY INVISIBLE (2302 3225);
FORCEADD TAP..6
R 2
(2300 3425);
FORCEPROP 3 LASTPIN (2250 3425) SIG_NAME M_K_DQS_DP<3>
J 0
(2260 3435);
DISPLAY 0.659574 (2260 3435);
PAINT MONO (2260 3435);
DISPLAY INVISIBLE (2260 3435);
FORCEPROP 1 LASTPIN (2250 3425) BN 3
J 2
(2300 3435);
DISPLAY 0.617021 (2300 3435);
PAINT PINK (2300 3435);
FORCEPROP 2 LAST CDS_LIB mstr_standard
J 0
(2300 3425);
DISPLAY 0.787234 (2300 3425);
PAINT MONO (2300 3425);
DISPLAY INVISIBLE (2300 3425);
FORCEPROP 1 LAST BODY_TYPE PLUMBING
J 2
(2300 3375);
DISPLAY 1.234043 (2300 3375);
PAINT GREEN (2300 3375);
DISPLAY INVISIBLE (2300 3375);
FORCEPROP 1 LAST HDL_TAP TRUE
J 2
(1975 3300);
DISPLAY 1.234043 (1975 3300);
PAINT GREEN (1975 3300);
DISPLAY INVISIBLE (1975 3300);
FORCEPROP 1 LAST PATH I147
J 2
(2302 3425);
DISPLAY 0.872340 (2302 3425);
PAINT GREEN (2302 3425);
DISPLAY INVISIBLE (2302 3425);
FORCEADD TAP..6
R 2
(2300 3525);
FORCEPROP 3 LASTPIN (2250 3525) SIG_NAME M_K_DQS_DP<4>
J 0
(2260 3535);
DISPLAY 0.659574 (2260 3535);
PAINT MONO (2260 3535);
DISPLAY INVISIBLE (2260 3535);
FORCEPROP 1 LASTPIN (2250 3525) BN 4
J 2
(2300 3535);
DISPLAY 0.617021 (2300 3535);
PAINT PINK (2300 3535);
FORCEPROP 2 LAST CDS_LIB mstr_standard
J 0
(2300 3525);
DISPLAY 0.787234 (2300 3525);
PAINT MONO (2300 3525);
DISPLAY INVISIBLE (2300 3525);
FORCEPROP 1 LAST BODY_TYPE PLUMBING
J 2
(2300 3475);
DISPLAY 1.234043 (2300 3475);
PAINT GREEN (2300 3475);
DISPLAY INVISIBLE (2300 3475);
FORCEPROP 1 LAST HDL_TAP TRUE
J 2
(1975 3400);
DISPLAY 1.234043 (1975 3400);
PAINT GREEN (1975 3400);
DISPLAY INVISIBLE (1975 3400);
FORCEPROP 1 LAST PATH I148
J 2
(2302 3525);
DISPLAY 0.872340 (2302 3525);
PAINT GREEN (2302 3525);
DISPLAY INVISIBLE (2302 3525);
FORCEADD TAP..6
R 2
(2300 3625);
FORCEPROP 3 LASTPIN (2250 3625) SIG_NAME M_K_DQS_DP<5>
J 0
(2260 3635);
DISPLAY 0.659574 (2260 3635);
PAINT MONO (2260 3635);
DISPLAY INVISIBLE (2260 3635);
FORCEPROP 1 LASTPIN (2250 3625) BN 5
J 2
(2300 3635);
DISPLAY 0.617021 (2300 3635);
PAINT PINK (2300 3635);
FORCEPROP 2 LAST CDS_LIB mstr_standard
J 0
(2300 3625);
DISPLAY 0.787234 (2300 3625);
PAINT MONO (2300 3625);
DISPLAY INVISIBLE (2300 3625);
FORCEPROP 1 LAST BODY_TYPE PLUMBING
J 2
(2300 3575);
DISPLAY 1.234043 (2300 3575);
PAINT GREEN (2300 3575);
DISPLAY INVISIBLE (2300 3575);
FORCEPROP 1 LAST HDL_TAP TRUE
J 2
(1975 3500);
DISPLAY 1.234043 (1975 3500);
PAINT GREEN (1975 3500);
DISPLAY INVISIBLE (1975 3500);
FORCEPROP 1 LAST PATH I149
J 2
(2302 3625);
DISPLAY 0.872340 (2302 3625);
PAINT GREEN (2302 3625);
DISPLAY INVISIBLE (2302 3625);
FORCEADD OFFPAGE..1
(-2250 2375);
FORCEPROP 2 LAST $XR5 88 
J 0
(-2951 2375);
DISPLAY 0.638298 (-2951 2375);
PAINT MONO (-2951 2375);
FORCEPROP 2 LAST $XR4 87 
J 0
(-2861 2375);
DISPLAY 0.638298 (-2861 2375);
PAINT MONO (-2861 2375);
FORCEPROP 2 LAST $XR3 86 
J 0
(-2771 2375);
DISPLAY 0.638298 (-2771 2375);
PAINT MONO (-2771 2375);
FORCEPROP 2 LAST $XR2 85 
J 0
(-2681 2375);
DISPLAY 0.638298 (-2681 2375);
PAINT MONO (-2681 2375);
FORCEPROP 2 LAST $XR1 83 
J 0
(-2591 2375);
DISPLAY 0.638298 (-2591 2375);
PAINT MONO (-2591 2375);
FORCEPROP 2 LAST $XR0 55 
J 0
(-2501 2375);
DISPLAY 0.638298 (-2501 2375);
PAINT MONO (-2501 2375);
FORCEPROP 2 LAST CDS_LIB mstr_standard
J 0
(-2250 2375);
DISPLAY 0.787234 (-2250 2375);
PAINT MONO (-2250 2375);
DISPLAY INVISIBLE (-2250 2375);
FORCEPROP 1 LAST OFFPAGE TRUE
J 0
(-1925 2250);
DISPLAY 0.936170 (-1925 2250);
PAINT GREEN (-1925 2250);
DISPLAY INVISIBLE (-1925 2250);
FORCEPROP 1 LAST COMMENT_BODY TRUE
J 0
(-2125 2275);
DISPLAY 0.936170 (-2125 2275);
PAINT GREEN (-2125 2275);
DISPLAY INVISIBLE (-2125 2275);
FORCEPROP 2 LAST PATH I15
J 0
(-2500 2425);
DISPLAY 1.021277 (-2500 2425);
PAINT ORANGE (-2500 2425);
DISPLAY INVISIBLE (-2500 2425);
FORCEADD TAP..6
R 2
(2500 3275);
FORCEPROP 3 LASTPIN (2450 3275) SIG_NAME M_K_DQS_DN<2>
J 0
(2460 3285);
DISPLAY 0.659574 (2460 3285);
PAINT MONO (2460 3285);
DISPLAY INVISIBLE (2460 3285);
FORCEPROP 1 LASTPIN (2450 3275) BN 2
J 2
(2500 3285);
DISPLAY 0.617021 (2500 3285);
PAINT PINK (2500 3285);
FORCEPROP 2 LAST CDS_LIB mstr_standard
J 0
(2500 3275);
DISPLAY 0.787234 (2500 3275);
PAINT MONO (2500 3275);
DISPLAY INVISIBLE (2500 3275);
FORCEPROP 1 LAST BODY_TYPE PLUMBING
J 2
(2500 3225);
DISPLAY 1.234043 (2500 3225);
PAINT GREEN (2500 3225);
DISPLAY INVISIBLE (2500 3225);
FORCEPROP 1 LAST HDL_TAP TRUE
J 2
(2175 3150);
DISPLAY 1.234043 (2175 3150);
PAINT GREEN (2175 3150);
DISPLAY INVISIBLE (2175 3150);
FORCEPROP 1 LAST PATH I150
J 2
(2502 3275);
DISPLAY 0.872340 (2502 3275);
PAINT GREEN (2502 3275);
DISPLAY INVISIBLE (2502 3275);
FORCEADD TAP..6
R 2
(2500 3375);
FORCEPROP 3 LASTPIN (2450 3375) SIG_NAME M_K_DQS_DN<3>
J 0
(2460 3385);
DISPLAY 0.659574 (2460 3385);
PAINT MONO (2460 3385);
DISPLAY INVISIBLE (2460 3385);
FORCEPROP 1 LASTPIN (2450 3375) BN 3
J 2
(2500 3385);
DISPLAY 0.617021 (2500 3385);
PAINT PINK (2500 3385);
FORCEPROP 2 LAST CDS_LIB mstr_standard
J 0
(2500 3375);
DISPLAY 0.787234 (2500 3375);
PAINT MONO (2500 3375);
DISPLAY INVISIBLE (2500 3375);
FORCEPROP 1 LAST BODY_TYPE PLUMBING
J 2
(2500 3325);
DISPLAY 1.234043 (2500 3325);
PAINT GREEN (2500 3325);
DISPLAY INVISIBLE (2500 3325);
FORCEPROP 1 LAST HDL_TAP TRUE
J 2
(2175 3250);
DISPLAY 1.234043 (2175 3250);
PAINT GREEN (2175 3250);
DISPLAY INVISIBLE (2175 3250);
FORCEPROP 1 LAST PATH I151
J 2
(2502 3375);
DISPLAY 0.872340 (2502 3375);
PAINT GREEN (2502 3375);
DISPLAY INVISIBLE (2502 3375);
FORCEADD TAP..6
R 2
(2500 3675);
FORCEPROP 3 LASTPIN (2450 3675) SIG_NAME M_K_DQS_DN<6>
J 0
(2460 3685);
DISPLAY 0.659574 (2460 3685);
PAINT MONO (2460 3685);
DISPLAY INVISIBLE (2460 3685);
FORCEPROP 1 LASTPIN (2450 3675) BN 6
J 2
(2500 3685);
DISPLAY 0.617021 (2500 3685);
PAINT PINK (2500 3685);
FORCEPROP 2 LAST CDS_LIB mstr_standard
J 0
(2500 3675);
DISPLAY 0.787234 (2500 3675);
PAINT MONO (2500 3675);
DISPLAY INVISIBLE (2500 3675);
FORCEPROP 1 LAST BODY_TYPE PLUMBING
J 2
(2500 3625);
DISPLAY 1.234043 (2500 3625);
PAINT GREEN (2500 3625);
DISPLAY INVISIBLE (2500 3625);
FORCEPROP 1 LAST HDL_TAP TRUE
J 2
(2175 3550);
DISPLAY 1.234043 (2175 3550);
PAINT GREEN (2175 3550);
DISPLAY INVISIBLE (2175 3550);
FORCEPROP 1 LAST PATH I152
J 2
(2502 3675);
DISPLAY 0.872340 (2502 3675);
PAINT GREEN (2502 3675);
DISPLAY INVISIBLE (2502 3675);
FORCEADD TAP..6
R 2
(2500 3575);
FORCEPROP 3 LASTPIN (2450 3575) SIG_NAME M_K_DQS_DN<5>
J 0
(2460 3585);
DISPLAY 0.659574 (2460 3585);
PAINT MONO (2460 3585);
DISPLAY INVISIBLE (2460 3585);
FORCEPROP 1 LASTPIN (2450 3575) BN 5
J 2
(2500 3585);
DISPLAY 0.617021 (2500 3585);
PAINT PINK (2500 3585);
FORCEPROP 2 LAST CDS_LIB mstr_standard
J 0
(2500 3575);
DISPLAY 0.787234 (2500 3575);
PAINT MONO (2500 3575);
DISPLAY INVISIBLE (2500 3575);
FORCEPROP 1 LAST BODY_TYPE PLUMBING
J 2
(2500 3525);
DISPLAY 1.234043 (2500 3525);
PAINT GREEN (2500 3525);
DISPLAY INVISIBLE (2500 3525);
FORCEPROP 1 LAST HDL_TAP TRUE
J 2
(2175 3450);
DISPLAY 1.234043 (2175 3450);
PAINT GREEN (2175 3450);
DISPLAY INVISIBLE (2175 3450);
FORCEPROP 1 LAST PATH I153
J 2
(2502 3575);
DISPLAY 0.872340 (2502 3575);
PAINT GREEN (2502 3575);
DISPLAY INVISIBLE (2502 3575);
FORCEADD TAP..6
R 2
(2500 3475);
FORCEPROP 3 LASTPIN (2450 3475) SIG_NAME M_K_DQS_DN<4>
J 0
(2460 3485);
DISPLAY 0.659574 (2460 3485);
PAINT MONO (2460 3485);
DISPLAY INVISIBLE (2460 3485);
FORCEPROP 1 LASTPIN (2450 3475) BN 4
J 2
(2500 3485);
DISPLAY 0.617021 (2500 3485);
PAINT PINK (2500 3485);
FORCEPROP 2 LAST CDS_LIB mstr_standard
J 0
(2500 3475);
DISPLAY 0.787234 (2500 3475);
PAINT MONO (2500 3475);
DISPLAY INVISIBLE (2500 3475);
FORCEPROP 1 LAST BODY_TYPE PLUMBING
J 2
(2500 3425);
DISPLAY 1.234043 (2500 3425);
PAINT GREEN (2500 3425);
DISPLAY INVISIBLE (2500 3425);
FORCEPROP 1 LAST HDL_TAP TRUE
J 2
(2175 3350);
DISPLAY 1.234043 (2175 3350);
PAINT GREEN (2175 3350);
DISPLAY INVISIBLE (2175 3350);
FORCEPROP 1 LAST PATH I154
J 2
(2502 3475);
DISPLAY 0.872340 (2502 3475);
PAINT GREEN (2502 3475);
DISPLAY INVISIBLE (2502 3475);
FORCEADD GND..1
R 2
(4100 725);
FORCEPROP 3 LASTPIN (4100 775) SIG_NAME GND\g
J 0
(4110 785);
DISPLAY 0.659574 (4110 785);
PAINT MONO (4110 785);
DISPLAY INVISIBLE (4110 785);
FORCEPROP 1 LAST VOLTAGE 0
J 0
(4100 725);
PAINT SKYBLUE (4100 725);
DISPLAY INVISIBLE (4100 725);
FORCEPROP 2 LAST CDS_LIB mstr_symbols
J 0
(4100 725);
DISPLAY 0.787234 (4100 725);
PAINT MONO (4100 725);
DISPLAY INVISIBLE (4100 725);
FORCEPROP 1 LAST SIZE 1B
J 2
(4025 675);
DISPLAY 1.170213 (4025 675);
PAINT GREEN (4025 675);
DISPLAY INVISIBLE (4025 675);
FORCEPROP 2 LAST BOM_COST MEM
J 0
(4100 730);
PAINT ORANGE (4100 730);
DISPLAY INVISIBLE (4100 730);
FORCEPROP 1 LAST BODY_TYPE PLUMBING
J 2
(4145 682);
DISPLAY 0.340426 (4145 682);
PAINT GREEN (4145 682);
DISPLAY INVISIBLE (4145 682);
FORCEPROP 1 LAST PATH I155
J 2
(4025 725);
DISPLAY 0.872340 (4025 725);
PAINT AQUA (4025 725);
DISPLAY INVISIBLE (4025 725);
FORCEPROP 2 LAST ROOM DDR4_CH_C
J 0
(4100 730);
PAINT ORANGE (4100 730);
DISPLAY INVISIBLE (4100 730);
FORCEPROP 1 LAST HDL_POWER GND
J 2
(4100 875);
DISPLAY 0.553191 (4100 875);
PAINT GREEN (4100 875);
DISPLAY INVISIBLE (4100 875);
FORCEADD TAP..6
R 2
(2300 3725);
FORCEPROP 3 LASTPIN (2250 3725) SIG_NAME M_K_DQS_DP<6>
J 0
(2260 3735);
DISPLAY 0.659574 (2260 3735);
PAINT MONO (2260 3735);
DISPLAY INVISIBLE (2260 3735);
FORCEPROP 1 LASTPIN (2250 3725) BN 6
J 2
(2300 3735);
DISPLAY 0.617021 (2300 3735);
PAINT PINK (2300 3735);
FORCEPROP 2 LAST CDS_LIB mstr_standard
J 0
(2300 3725);
DISPLAY 0.787234 (2300 3725);
PAINT MONO (2300 3725);
DISPLAY INVISIBLE (2300 3725);
FORCEPROP 1 LAST BODY_TYPE PLUMBING
J 2
(2300 3675);
DISPLAY 1.234043 (2300 3675);
PAINT GREEN (2300 3675);
DISPLAY INVISIBLE (2300 3675);
FORCEPROP 1 LAST HDL_TAP TRUE
J 2
(1975 3600);
DISPLAY 1.234043 (1975 3600);
PAINT GREEN (1975 3600);
DISPLAY INVISIBLE (1975 3600);
FORCEPROP 1 LAST PATH I156
J 2
(2302 3725);
DISPLAY 0.872340 (2302 3725);
PAINT GREEN (2302 3725);
DISPLAY INVISIBLE (2302 3725);
FORCEADD TAP..6
R 2
(2300 3825);
FORCEPROP 3 LASTPIN (2250 3825) SIG_NAME M_K_DQS_DP<7>
J 0
(2260 3835);
DISPLAY 0.659574 (2260 3835);
PAINT MONO (2260 3835);
DISPLAY INVISIBLE (2260 3835);
FORCEPROP 1 LASTPIN (2250 3825) BN 7
J 2
(2300 3835);
DISPLAY 0.617021 (2300 3835);
PAINT PINK (2300 3835);
FORCEPROP 2 LAST CDS_LIB mstr_standard
J 0
(2300 3825);
DISPLAY 0.787234 (2300 3825);
PAINT MONO (2300 3825);
DISPLAY INVISIBLE (2300 3825);
FORCEPROP 1 LAST BODY_TYPE PLUMBING
J 2
(2300 3775);
DISPLAY 1.234043 (2300 3775);
PAINT GREEN (2300 3775);
DISPLAY INVISIBLE (2300 3775);
FORCEPROP 1 LAST HDL_TAP TRUE
J 2
(1975 3700);
DISPLAY 1.234043 (1975 3700);
PAINT GREEN (1975 3700);
DISPLAY INVISIBLE (1975 3700);
FORCEPROP 1 LAST PATH I157
J 2
(2302 3825);
DISPLAY 0.872340 (2302 3825);
PAINT GREEN (2302 3825);
DISPLAY INVISIBLE (2302 3825);
FORCEADD TAP..6
R 2
(2300 3925);
FORCEPROP 3 LASTPIN (2250 3925) SIG_NAME M_K_DQS_DP<8>
J 0
(2260 3935);
DISPLAY 0.659574 (2260 3935);
PAINT MONO (2260 3935);
DISPLAY INVISIBLE (2260 3935);
FORCEPROP 1 LASTPIN (2250 3925) BN 8
J 2
(2300 3935);
DISPLAY 0.617021 (2300 3935);
PAINT PINK (2300 3935);
FORCEPROP 2 LAST CDS_LIB mstr_standard
J 0
(2300 3925);
DISPLAY 0.787234 (2300 3925);
PAINT MONO (2300 3925);
DISPLAY INVISIBLE (2300 3925);
FORCEPROP 1 LAST BODY_TYPE PLUMBING
J 2
(2300 3875);
DISPLAY 1.234043 (2300 3875);
PAINT GREEN (2300 3875);
DISPLAY INVISIBLE (2300 3875);
FORCEPROP 1 LAST HDL_TAP TRUE
J 2
(1975 3800);
DISPLAY 1.234043 (1975 3800);
PAINT GREEN (1975 3800);
DISPLAY INVISIBLE (1975 3800);
FORCEPROP 1 LAST PATH I158
J 2
(2302 3925);
DISPLAY 0.872340 (2302 3925);
PAINT GREEN (2302 3925);
DISPLAY INVISIBLE (2302 3925);
FORCEADD TAP..6
R 2
(2300 4025);
FORCEPROP 3 LASTPIN (2250 4025) SIG_NAME M_K_DQS_DP<9>
J 0
(2260 4035);
DISPLAY 0.659574 (2260 4035);
PAINT MONO (2260 4035);
DISPLAY INVISIBLE (2260 4035);
FORCEPROP 1 LASTPIN (2250 4025) BN 9
J 2
(2300 4035);
DISPLAY 0.617021 (2300 4035);
PAINT PINK (2300 4035);
FORCEPROP 2 LAST CDS_LIB mstr_standard
J 0
(2300 4025);
DISPLAY 0.787234 (2300 4025);
PAINT MONO (2300 4025);
DISPLAY INVISIBLE (2300 4025);
FORCEPROP 1 LAST BODY_TYPE PLUMBING
J 2
(2300 3975);
DISPLAY 1.234043 (2300 3975);
PAINT GREEN (2300 3975);
DISPLAY INVISIBLE (2300 3975);
FORCEPROP 1 LAST HDL_TAP TRUE
J 2
(1975 3900);
DISPLAY 1.234043 (1975 3900);
PAINT GREEN (1975 3900);
DISPLAY INVISIBLE (1975 3900);
FORCEPROP 1 LAST PATH I159
J 2
(2302 4025);
DISPLAY 0.872340 (2302 4025);
PAINT GREEN (2302 4025);
DISPLAY INVISIBLE (2302 4025);
FORCEADD OFFPAGE..1
(-2250 2425);
FORCEPROP 2 LAST $XR1 83 
J 0
(-2591 2425);
DISPLAY 0.638298 (-2591 2425);
PAINT MONO (-2591 2425);
FORCEPROP 2 LAST $XR0 60 
J 0
(-2501 2425);
DISPLAY 0.638298 (-2501 2425);
PAINT MONO (-2501 2425);
FORCEPROP 2 LAST CDS_LIB mstr_standard
J 0
(-2250 2425);
DISPLAY 0.787234 (-2250 2425);
PAINT MONO (-2250 2425);
DISPLAY INVISIBLE (-2250 2425);
FORCEPROP 1 LAST OFFPAGE TRUE
J 0
(-1925 2300);
DISPLAY 0.936170 (-1925 2300);
PAINT GREEN (-1925 2300);
DISPLAY INVISIBLE (-1925 2300);
FORCEPROP 1 LAST COMMENT_BODY TRUE
J 0
(-2125 2325);
DISPLAY 0.936170 (-2125 2325);
PAINT GREEN (-2125 2325);
DISPLAY INVISIBLE (-2125 2325);
FORCEPROP 2 LAST PATH I16
J 0
(-2500 2475);
DISPLAY 1.021277 (-2500 2475);
PAINT ORANGE (-2500 2475);
DISPLAY INVISIBLE (-2500 2475);
FORCEADD TAP..6
R 2
(2300 4225);
FORCEPROP 3 LASTPIN (2250 4225) SIG_NAME M_K_DQS_DP<11>
J 0
(2260 4235);
DISPLAY 0.659574 (2260 4235);
PAINT MONO (2260 4235);
DISPLAY INVISIBLE (2260 4235);
FORCEPROP 1 LASTPIN (2250 4225) BN 11
J 2
(2300 4235);
DISPLAY 0.617021 (2300 4235);
PAINT PINK (2300 4235);
FORCEPROP 2 LAST CDS_LIB mstr_standard
J 0
(2300 4225);
DISPLAY 0.787234 (2300 4225);
PAINT MONO (2300 4225);
DISPLAY INVISIBLE (2300 4225);
FORCEPROP 1 LAST BODY_TYPE PLUMBING
J 2
(2300 4175);
DISPLAY 1.234043 (2300 4175);
PAINT GREEN (2300 4175);
DISPLAY INVISIBLE (2300 4175);
FORCEPROP 1 LAST HDL_TAP TRUE
J 2
(1975 4100);
DISPLAY 1.234043 (1975 4100);
PAINT GREEN (1975 4100);
DISPLAY INVISIBLE (1975 4100);
FORCEPROP 1 LAST PATH I160
J 2
(2302 4225);
DISPLAY 0.872340 (2302 4225);
PAINT GREEN (2302 4225);
DISPLAY INVISIBLE (2302 4225);
FORCEADD TAP..6
R 2
(2300 4125);
FORCEPROP 3 LASTPIN (2250 4125) SIG_NAME M_K_DQS_DP<10>
J 0
(2260 4135);
DISPLAY 0.659574 (2260 4135);
PAINT MONO (2260 4135);
DISPLAY INVISIBLE (2260 4135);
FORCEPROP 1 LASTPIN (2250 4125) BN 10
J 2
(2300 4135);
DISPLAY 0.617021 (2300 4135);
PAINT PINK (2300 4135);
FORCEPROP 2 LAST CDS_LIB mstr_standard
J 0
(2300 4125);
DISPLAY 0.787234 (2300 4125);
PAINT MONO (2300 4125);
DISPLAY INVISIBLE (2300 4125);
FORCEPROP 1 LAST BODY_TYPE PLUMBING
J 2
(2300 4075);
DISPLAY 1.234043 (2300 4075);
PAINT GREEN (2300 4075);
DISPLAY INVISIBLE (2300 4075);
FORCEPROP 1 LAST HDL_TAP TRUE
J 2
(1975 4000);
DISPLAY 1.234043 (1975 4000);
PAINT GREEN (1975 4000);
DISPLAY INVISIBLE (1975 4000);
FORCEPROP 1 LAST PATH I161
J 2
(2302 4125);
DISPLAY 0.872340 (2302 4125);
PAINT GREEN (2302 4125);
DISPLAY INVISIBLE (2302 4125);
FORCEADD TAP..6
R 2
(2500 3975);
FORCEPROP 3 LASTPIN (2450 3975) SIG_NAME M_K_DQS_DN<9>
J 0
(2460 3985);
DISPLAY 0.659574 (2460 3985);
PAINT MONO (2460 3985);
DISPLAY INVISIBLE (2460 3985);
FORCEPROP 1 LASTPIN (2450 3975) BN 9
J 2
(2500 3985);
DISPLAY 0.617021 (2500 3985);
PAINT PINK (2500 3985);
FORCEPROP 2 LAST CDS_LIB mstr_standard
J 0
(2500 3975);
DISPLAY 0.787234 (2500 3975);
PAINT MONO (2500 3975);
DISPLAY INVISIBLE (2500 3975);
FORCEPROP 1 LAST BODY_TYPE PLUMBING
J 2
(2500 3925);
DISPLAY 1.234043 (2500 3925);
PAINT GREEN (2500 3925);
DISPLAY INVISIBLE (2500 3925);
FORCEPROP 1 LAST HDL_TAP TRUE
J 2
(2175 3850);
DISPLAY 1.234043 (2175 3850);
PAINT GREEN (2175 3850);
DISPLAY INVISIBLE (2175 3850);
FORCEPROP 1 LAST PATH I162
J 2
(2502 3975);
DISPLAY 0.872340 (2502 3975);
PAINT GREEN (2502 3975);
DISPLAY INVISIBLE (2502 3975);
FORCEADD TAP..6
R 2
(2500 3775);
FORCEPROP 3 LASTPIN (2450 3775) SIG_NAME M_K_DQS_DN<7>
J 0
(2460 3785);
DISPLAY 0.659574 (2460 3785);
PAINT MONO (2460 3785);
DISPLAY INVISIBLE (2460 3785);
FORCEPROP 1 LASTPIN (2450 3775) BN 7
J 2
(2500 3785);
DISPLAY 0.617021 (2500 3785);
PAINT PINK (2500 3785);
FORCEPROP 2 LAST CDS_LIB mstr_standard
J 0
(2500 3775);
DISPLAY 0.787234 (2500 3775);
PAINT MONO (2500 3775);
DISPLAY INVISIBLE (2500 3775);
FORCEPROP 1 LAST BODY_TYPE PLUMBING
J 2
(2500 3725);
DISPLAY 1.234043 (2500 3725);
PAINT GREEN (2500 3725);
DISPLAY INVISIBLE (2500 3725);
FORCEPROP 1 LAST HDL_TAP TRUE
J 2
(2175 3650);
DISPLAY 1.234043 (2175 3650);
PAINT GREEN (2175 3650);
DISPLAY INVISIBLE (2175 3650);
FORCEPROP 1 LAST PATH I163
J 2
(2502 3775);
DISPLAY 0.872340 (2502 3775);
PAINT GREEN (2502 3775);
DISPLAY INVISIBLE (2502 3775);
FORCEADD TAP..6
R 2
(2500 3875);
FORCEPROP 3 LASTPIN (2450 3875) SIG_NAME M_K_DQS_DN<8>
J 0
(2460 3885);
DISPLAY 0.659574 (2460 3885);
PAINT MONO (2460 3885);
DISPLAY INVISIBLE (2460 3885);
FORCEPROP 1 LASTPIN (2450 3875) BN 8
J 2
(2500 3885);
DISPLAY 0.617021 (2500 3885);
PAINT PINK (2500 3885);
FORCEPROP 2 LAST CDS_LIB mstr_standard
J 0
(2500 3875);
DISPLAY 0.787234 (2500 3875);
PAINT MONO (2500 3875);
DISPLAY INVISIBLE (2500 3875);
FORCEPROP 1 LAST BODY_TYPE PLUMBING
J 2
(2500 3825);
DISPLAY 1.234043 (2500 3825);
PAINT GREEN (2500 3825);
DISPLAY INVISIBLE (2500 3825);
FORCEPROP 1 LAST HDL_TAP TRUE
J 2
(2175 3750);
DISPLAY 1.234043 (2175 3750);
PAINT GREEN (2175 3750);
DISPLAY INVISIBLE (2175 3750);
FORCEPROP 1 LAST PATH I164
J 2
(2502 3875);
DISPLAY 0.872340 (2502 3875);
PAINT GREEN (2502 3875);
DISPLAY INVISIBLE (2502 3875);
FORCEADD TAP..6
R 2
(2500 4175);
FORCEPROP 3 LASTPIN (2450 4175) SIG_NAME M_K_DQS_DN<11>
J 0
(2460 4185);
DISPLAY 0.659574 (2460 4185);
PAINT MONO (2460 4185);
DISPLAY INVISIBLE (2460 4185);
FORCEPROP 1 LASTPIN (2450 4175) BN 11
J 2
(2500 4185);
DISPLAY 0.617021 (2500 4185);
PAINT PINK (2500 4185);
FORCEPROP 2 LAST CDS_LIB mstr_standard
J 0
(2500 4175);
DISPLAY 0.787234 (2500 4175);
PAINT MONO (2500 4175);
DISPLAY INVISIBLE (2500 4175);
FORCEPROP 1 LAST BODY_TYPE PLUMBING
J 2
(2500 4125);
DISPLAY 1.234043 (2500 4125);
PAINT GREEN (2500 4125);
DISPLAY INVISIBLE (2500 4125);
FORCEPROP 1 LAST HDL_TAP TRUE
J 2
(2175 4050);
DISPLAY 1.234043 (2175 4050);
PAINT GREEN (2175 4050);
DISPLAY INVISIBLE (2175 4050);
FORCEPROP 1 LAST PATH I165
J 2
(2502 4175);
DISPLAY 0.872340 (2502 4175);
PAINT GREEN (2502 4175);
DISPLAY INVISIBLE (2502 4175);
FORCEADD TAP..6
R 2
(2500 4075);
FORCEPROP 3 LASTPIN (2450 4075) SIG_NAME M_K_DQS_DN<10>
J 0
(2460 4085);
DISPLAY 0.659574 (2460 4085);
PAINT MONO (2460 4085);
DISPLAY INVISIBLE (2460 4085);
FORCEPROP 1 LASTPIN (2450 4075) BN 10
J 2
(2500 4085);
DISPLAY 0.617021 (2500 4085);
PAINT PINK (2500 4085);
FORCEPROP 2 LAST CDS_LIB mstr_standard
J 0
(2500 4075);
DISPLAY 0.787234 (2500 4075);
PAINT MONO (2500 4075);
DISPLAY INVISIBLE (2500 4075);
FORCEPROP 1 LAST BODY_TYPE PLUMBING
J 2
(2500 4025);
DISPLAY 1.234043 (2500 4025);
PAINT GREEN (2500 4025);
DISPLAY INVISIBLE (2500 4025);
FORCEPROP 1 LAST HDL_TAP TRUE
J 2
(2175 3950);
DISPLAY 1.234043 (2175 3950);
PAINT GREEN (2175 3950);
DISPLAY INVISIBLE (2175 3950);
FORCEPROP 1 LAST PATH I166
J 2
(2502 4075);
DISPLAY 0.872340 (2502 4075);
PAINT GREEN (2502 4075);
DISPLAY INVISIBLE (2502 4075);
FORCEADD TAP..6
R 2
(2300 4325);
FORCEPROP 3 LASTPIN (2250 4325) SIG_NAME M_K_DQS_DP<12>
J 0
(2260 4335);
DISPLAY 0.659574 (2260 4335);
PAINT MONO (2260 4335);
DISPLAY INVISIBLE (2260 4335);
FORCEPROP 1 LASTPIN (2250 4325) BN 12
J 2
(2300 4335);
DISPLAY 0.617021 (2300 4335);
PAINT PINK (2300 4335);
FORCEPROP 2 LAST CDS_LIB mstr_standard
J 0
(2300 4325);
DISPLAY 0.787234 (2300 4325);
PAINT MONO (2300 4325);
DISPLAY INVISIBLE (2300 4325);
FORCEPROP 1 LAST BODY_TYPE PLUMBING
J 2
(2300 4275);
DISPLAY 1.234043 (2300 4275);
PAINT GREEN (2300 4275);
DISPLAY INVISIBLE (2300 4275);
FORCEPROP 1 LAST HDL_TAP TRUE
J 2
(1975 4200);
DISPLAY 1.234043 (1975 4200);
PAINT GREEN (1975 4200);
DISPLAY INVISIBLE (1975 4200);
FORCEPROP 1 LAST PATH I167
J 2
(2302 4325);
DISPLAY 0.872340 (2302 4325);
PAINT GREEN (2302 4325);
DISPLAY INVISIBLE (2302 4325);
FORCEADD TAP..6
R 2
(2300 4425);
FORCEPROP 3 LASTPIN (2250 4425) SIG_NAME M_K_DQS_DP<13>
J 0
(2260 4435);
DISPLAY 0.659574 (2260 4435);
PAINT MONO (2260 4435);
DISPLAY INVISIBLE (2260 4435);
FORCEPROP 1 LASTPIN (2250 4425) BN 13
J 2
(2300 4435);
DISPLAY 0.617021 (2300 4435);
PAINT PINK (2300 4435);
FORCEPROP 2 LAST CDS_LIB mstr_standard
J 0
(2300 4425);
DISPLAY 0.787234 (2300 4425);
PAINT MONO (2300 4425);
DISPLAY INVISIBLE (2300 4425);
FORCEPROP 1 LAST BODY_TYPE PLUMBING
J 2
(2300 4375);
DISPLAY 1.234043 (2300 4375);
PAINT GREEN (2300 4375);
DISPLAY INVISIBLE (2300 4375);
FORCEPROP 1 LAST HDL_TAP TRUE
J 2
(1975 4300);
DISPLAY 1.234043 (1975 4300);
PAINT GREEN (1975 4300);
DISPLAY INVISIBLE (1975 4300);
FORCEPROP 1 LAST PATH I168
J 2
(2302 4425);
DISPLAY 0.872340 (2302 4425);
PAINT GREEN (2302 4425);
DISPLAY INVISIBLE (2302 4425);
FORCEADD TAP..6
R 2
(2300 4525);
FORCEPROP 3 LASTPIN (2250 4525) SIG_NAME M_K_DQS_DP<14>
J 0
(2260 4535);
DISPLAY 0.659574 (2260 4535);
PAINT MONO (2260 4535);
DISPLAY INVISIBLE (2260 4535);
FORCEPROP 1 LASTPIN (2250 4525) BN 14
J 2
(2300 4535);
DISPLAY 0.617021 (2300 4535);
PAINT PINK (2300 4535);
FORCEPROP 2 LAST CDS_LIB mstr_standard
J 0
(2300 4525);
DISPLAY 0.787234 (2300 4525);
PAINT MONO (2300 4525);
DISPLAY INVISIBLE (2300 4525);
FORCEPROP 1 LAST BODY_TYPE PLUMBING
J 2
(2300 4475);
DISPLAY 1.234043 (2300 4475);
PAINT GREEN (2300 4475);
DISPLAY INVISIBLE (2300 4475);
FORCEPROP 1 LAST HDL_TAP TRUE
J 2
(1975 4400);
DISPLAY 1.234043 (1975 4400);
PAINT GREEN (1975 4400);
DISPLAY INVISIBLE (1975 4400);
FORCEPROP 1 LAST PATH I169
J 2
(2302 4525);
DISPLAY 0.872340 (2302 4525);
PAINT GREEN (2302 4525);
DISPLAY INVISIBLE (2302 4525);
FORCEADD OFFPAGE..1
(-2250 2625);
FORCEPROP 2 LAST $XR1 83 
J 0
(-2591 2625);
DISPLAY 0.638298 (-2591 2625);
PAINT MONO (-2591 2625);
FORCEPROP 2 LAST $XR0 60 
J 0
(-2501 2625);
DISPLAY 0.638298 (-2501 2625);
PAINT MONO (-2501 2625);
FORCEPROP 2 LAST CDS_LIB mstr_standard
J 0
(-2250 2625);
DISPLAY 0.787234 (-2250 2625);
PAINT MONO (-2250 2625);
DISPLAY INVISIBLE (-2250 2625);
FORCEPROP 1 LAST OFFPAGE TRUE
J 0
(-1925 2500);
DISPLAY 0.936170 (-1925 2500);
PAINT GREEN (-1925 2500);
DISPLAY INVISIBLE (-1925 2500);
FORCEPROP 1 LAST COMMENT_BODY TRUE
J 0
(-2125 2525);
DISPLAY 0.936170 (-2125 2525);
PAINT GREEN (-2125 2525);
DISPLAY INVISIBLE (-2125 2525);
FORCEPROP 2 LAST PATH I17
J 0
(-2500 2675);
DISPLAY 1.021277 (-2500 2675);
PAINT ORANGE (-2500 2675);
DISPLAY INVISIBLE (-2500 2675);
FORCEADD TAP..6
R 2
(2300 4625);
FORCEPROP 3 LASTPIN (2250 4625) SIG_NAME M_K_DQS_DP<15>
J 0
(2260 4635);
DISPLAY 0.659574 (2260 4635);
PAINT MONO (2260 4635);
DISPLAY INVISIBLE (2260 4635);
FORCEPROP 1 LASTPIN (2250 4625) BN 15
J 2
(2300 4635);
DISPLAY 0.617021 (2300 4635);
PAINT PINK (2300 4635);
FORCEPROP 2 LAST CDS_LIB mstr_standard
J 0
(2300 4625);
DISPLAY 0.787234 (2300 4625);
PAINT MONO (2300 4625);
DISPLAY INVISIBLE (2300 4625);
FORCEPROP 1 LAST BODY_TYPE PLUMBING
J 2
(2300 4575);
DISPLAY 1.234043 (2300 4575);
PAINT GREEN (2300 4575);
DISPLAY INVISIBLE (2300 4575);
FORCEPROP 1 LAST HDL_TAP TRUE
J 2
(1975 4500);
DISPLAY 1.234043 (1975 4500);
PAINT GREEN (1975 4500);
DISPLAY INVISIBLE (1975 4500);
FORCEPROP 1 LAST PATH I170
J 2
(2302 4625);
DISPLAY 0.872340 (2302 4625);
PAINT GREEN (2302 4625);
DISPLAY INVISIBLE (2302 4625);
FORCEADD TAP..6
R 2
(2300 4725);
FORCEPROP 3 LASTPIN (2250 4725) SIG_NAME M_K_DQS_DP<16>
J 0
(2260 4735);
DISPLAY 0.659574 (2260 4735);
PAINT MONO (2260 4735);
DISPLAY INVISIBLE (2260 4735);
FORCEPROP 1 LASTPIN (2250 4725) BN 16
J 2
(2300 4735);
DISPLAY 0.617021 (2300 4735);
PAINT PINK (2300 4735);
FORCEPROP 2 LAST CDS_LIB mstr_standard
J 0
(2300 4725);
DISPLAY 0.787234 (2300 4725);
PAINT MONO (2300 4725);
DISPLAY INVISIBLE (2300 4725);
FORCEPROP 1 LAST BODY_TYPE PLUMBING
J 2
(2300 4675);
DISPLAY 1.234043 (2300 4675);
PAINT GREEN (2300 4675);
DISPLAY INVISIBLE (2300 4675);
FORCEPROP 1 LAST HDL_TAP TRUE
J 2
(1975 4600);
DISPLAY 1.234043 (1975 4600);
PAINT GREEN (1975 4600);
DISPLAY INVISIBLE (1975 4600);
FORCEPROP 1 LAST PATH I171
J 2
(2302 4725);
DISPLAY 0.872340 (2302 4725);
PAINT GREEN (2302 4725);
DISPLAY INVISIBLE (2302 4725);
FORCEADD TAP..6
R 2
(2500 4475);
FORCEPROP 3 LASTPIN (2450 4475) SIG_NAME M_K_DQS_DN<14>
J 0
(2460 4485);
DISPLAY 0.659574 (2460 4485);
PAINT MONO (2460 4485);
DISPLAY INVISIBLE (2460 4485);
FORCEPROP 1 LASTPIN (2450 4475) BN 14
J 2
(2500 4485);
DISPLAY 0.617021 (2500 4485);
PAINT PINK (2500 4485);
FORCEPROP 2 LAST CDS_LIB mstr_standard
J 0
(2500 4475);
DISPLAY 0.787234 (2500 4475);
PAINT MONO (2500 4475);
DISPLAY INVISIBLE (2500 4475);
FORCEPROP 1 LAST BODY_TYPE PLUMBING
J 2
(2500 4425);
DISPLAY 1.234043 (2500 4425);
PAINT GREEN (2500 4425);
DISPLAY INVISIBLE (2500 4425);
FORCEPROP 1 LAST HDL_TAP TRUE
J 2
(2175 4350);
DISPLAY 1.234043 (2175 4350);
PAINT GREEN (2175 4350);
DISPLAY INVISIBLE (2175 4350);
FORCEPROP 1 LAST PATH I172
J 2
(2502 4475);
DISPLAY 0.872340 (2502 4475);
PAINT GREEN (2502 4475);
DISPLAY INVISIBLE (2502 4475);
FORCEADD TAP..6
R 2
(2500 4275);
FORCEPROP 3 LASTPIN (2450 4275) SIG_NAME M_K_DQS_DN<12>
J 0
(2460 4285);
DISPLAY 0.659574 (2460 4285);
PAINT MONO (2460 4285);
DISPLAY INVISIBLE (2460 4285);
FORCEPROP 1 LASTPIN (2450 4275) BN 12
J 2
(2500 4285);
DISPLAY 0.617021 (2500 4285);
PAINT PINK (2500 4285);
FORCEPROP 2 LAST CDS_LIB mstr_standard
J 0
(2500 4275);
DISPLAY 0.787234 (2500 4275);
PAINT MONO (2500 4275);
DISPLAY INVISIBLE (2500 4275);
FORCEPROP 1 LAST BODY_TYPE PLUMBING
J 2
(2500 4225);
DISPLAY 1.234043 (2500 4225);
PAINT GREEN (2500 4225);
DISPLAY INVISIBLE (2500 4225);
FORCEPROP 1 LAST HDL_TAP TRUE
J 2
(2175 4150);
DISPLAY 1.234043 (2175 4150);
PAINT GREEN (2175 4150);
DISPLAY INVISIBLE (2175 4150);
FORCEPROP 1 LAST PATH I173
J 2
(2502 4275);
DISPLAY 0.872340 (2502 4275);
PAINT GREEN (2502 4275);
DISPLAY INVISIBLE (2502 4275);
FORCEADD TAP..6
R 2
(2500 4375);
FORCEPROP 3 LASTPIN (2450 4375) SIG_NAME M_K_DQS_DN<13>
J 0
(2460 4385);
DISPLAY 0.659574 (2460 4385);
PAINT MONO (2460 4385);
DISPLAY INVISIBLE (2460 4385);
FORCEPROP 1 LASTPIN (2450 4375) BN 13
J 2
(2500 4385);
DISPLAY 0.617021 (2500 4385);
PAINT PINK (2500 4385);
FORCEPROP 2 LAST CDS_LIB mstr_standard
J 0
(2500 4375);
DISPLAY 0.787234 (2500 4375);
PAINT MONO (2500 4375);
DISPLAY INVISIBLE (2500 4375);
FORCEPROP 1 LAST BODY_TYPE PLUMBING
J 2
(2500 4325);
DISPLAY 1.234043 (2500 4325);
PAINT GREEN (2500 4325);
DISPLAY INVISIBLE (2500 4325);
FORCEPROP 1 LAST HDL_TAP TRUE
J 2
(2175 4250);
DISPLAY 1.234043 (2175 4250);
PAINT GREEN (2175 4250);
DISPLAY INVISIBLE (2175 4250);
FORCEPROP 1 LAST PATH I174
J 2
(2502 4375);
DISPLAY 0.872340 (2502 4375);
PAINT GREEN (2502 4375);
DISPLAY INVISIBLE (2502 4375);
FORCEADD TAP..6
R 2
(2500 4675);
FORCEPROP 3 LASTPIN (2450 4675) SIG_NAME M_K_DQS_DN<16>
J 0
(2460 4685);
DISPLAY 0.659574 (2460 4685);
PAINT MONO (2460 4685);
DISPLAY INVISIBLE (2460 4685);
FORCEPROP 1 LASTPIN (2450 4675) BN 16
J 2
(2500 4685);
DISPLAY 0.617021 (2500 4685);
PAINT PINK (2500 4685);
FORCEPROP 2 LAST CDS_LIB mstr_standard
J 0
(2500 4675);
DISPLAY 0.787234 (2500 4675);
PAINT MONO (2500 4675);
DISPLAY INVISIBLE (2500 4675);
FORCEPROP 1 LAST BODY_TYPE PLUMBING
J 2
(2500 4625);
DISPLAY 1.234043 (2500 4625);
PAINT GREEN (2500 4625);
DISPLAY INVISIBLE (2500 4625);
FORCEPROP 1 LAST HDL_TAP TRUE
J 2
(2175 4550);
DISPLAY 1.234043 (2175 4550);
PAINT GREEN (2175 4550);
DISPLAY INVISIBLE (2175 4550);
FORCEPROP 1 LAST PATH I175
J 2
(2502 4675);
DISPLAY 0.872340 (2502 4675);
PAINT GREEN (2502 4675);
DISPLAY INVISIBLE (2502 4675);
FORCEADD TAP..6
R 2
(2500 4575);
FORCEPROP 3 LASTPIN (2450 4575) SIG_NAME M_K_DQS_DN<15>
J 0
(2460 4585);
DISPLAY 0.659574 (2460 4585);
PAINT MONO (2460 4585);
DISPLAY INVISIBLE (2460 4585);
FORCEPROP 1 LASTPIN (2450 4575) BN 15
J 2
(2500 4585);
DISPLAY 0.617021 (2500 4585);
PAINT PINK (2500 4585);
FORCEPROP 2 LAST CDS_LIB mstr_standard
J 0
(2500 4575);
DISPLAY 0.787234 (2500 4575);
PAINT MONO (2500 4575);
DISPLAY INVISIBLE (2500 4575);
FORCEPROP 1 LAST BODY_TYPE PLUMBING
J 2
(2500 4525);
DISPLAY 1.234043 (2500 4525);
PAINT GREEN (2500 4525);
DISPLAY INVISIBLE (2500 4525);
FORCEPROP 1 LAST HDL_TAP TRUE
J 2
(2175 4450);
DISPLAY 1.234043 (2175 4450);
PAINT GREEN (2175 4450);
DISPLAY INVISIBLE (2175 4450);
FORCEPROP 1 LAST PATH I176
J 2
(2502 4575);
DISPLAY 0.872340 (2502 4575);
PAINT GREEN (2502 4575);
DISPLAY INVISIBLE (2502 4575);
FORCEADD TAP..6
R 2
(2300 4825);
FORCEPROP 3 LASTPIN (2250 4825) SIG_NAME M_K_DQS_DP<17>
J 0
(2260 4835);
DISPLAY 0.659574 (2260 4835);
PAINT MONO (2260 4835);
DISPLAY INVISIBLE (2260 4835);
FORCEPROP 1 LASTPIN (2250 4825) BN 17
J 2
(2300 4835);
DISPLAY 0.617021 (2300 4835);
PAINT PINK (2300 4835);
FORCEPROP 2 LAST CDS_LIB mstr_standard
J 2
(2300 4825);
DISPLAY 0.787234 (2300 4825);
PAINT MONO (2300 4825);
DISPLAY INVISIBLE (2300 4825);
FORCEPROP 1 LAST BODY_TYPE PLUMBING
J 2
(2300 4775);
DISPLAY 1.234043 (2300 4775);
PAINT GREEN (2300 4775);
DISPLAY INVISIBLE (2300 4775);
FORCEPROP 1 LAST HDL_TAP TRUE
J 2
(1975 4700);
DISPLAY 1.234043 (1975 4700);
PAINT GREEN (1975 4700);
DISPLAY INVISIBLE (1975 4700);
FORCEPROP 1 LAST PATH I177
J 2
(2302 4825);
DISPLAY 0.872340 (2302 4825);
PAINT GREEN (2302 4825);
DISPLAY INVISIBLE (2302 4825);
FORCEADD TAP..6
R 2
(2500 4775);
FORCEPROP 3 LASTPIN (2450 4775) SIG_NAME M_K_DQS_DN<17>
J 0
(2460 4785);
DISPLAY 0.659574 (2460 4785);
PAINT MONO (2460 4785);
DISPLAY INVISIBLE (2460 4785);
FORCEPROP 1 LASTPIN (2450 4775) BN 17
J 2
(2500 4785);
DISPLAY 0.617021 (2500 4785);
PAINT PINK (2500 4785);
FORCEPROP 2 LAST CDS_LIB mstr_standard
J 2
(2500 4775);
DISPLAY 0.787234 (2500 4775);
PAINT MONO (2500 4775);
DISPLAY INVISIBLE (2500 4775);
FORCEPROP 1 LAST BODY_TYPE PLUMBING
J 2
(2500 4725);
DISPLAY 1.234043 (2500 4725);
PAINT GREEN (2500 4725);
DISPLAY INVISIBLE (2500 4725);
FORCEPROP 1 LAST HDL_TAP TRUE
J 2
(2175 4650);
DISPLAY 1.234043 (2175 4650);
PAINT GREEN (2175 4650);
DISPLAY INVISIBLE (2175 4650);
FORCEPROP 1 LAST PATH I178
J 2
(2502 4775);
DISPLAY 0.872340 (2502 4775);
PAINT GREEN (2502 4775);
DISPLAY INVISIBLE (2502 4775);
FORCEADD OFFPAGE..3
(3200 4825);
FORCEPROP 2 LAST $XR1 83 
J 0
(3504 4825);
DISPLAY 0.638298 (3504 4825);
PAINT MONO (3504 4825);
FORCEPROP 2 LAST $XR0 60 
J 0
(3414 4825);
DISPLAY 0.638298 (3414 4825);
PAINT MONO (3414 4825);
FORCEPROP 2 LAST CDS_LIB mstr_standard
J 0
(3200 4825);
DISPLAY 0.787234 (3200 4825);
PAINT MONO (3200 4825);
DISPLAY INVISIBLE (3200 4825);
FORCEPROP 1 LAST OFFPAGE TRUE
J 0
(3525 4700);
DISPLAY 0.936170 (3525 4700);
PAINT GREEN (3525 4700);
DISPLAY INVISIBLE (3525 4700);
FORCEPROP 1 LAST COMMENT_BODY TRUE
J 0
(3150 4725);
DISPLAY 0.936170 (3150 4725);
PAINT GREEN (3150 4725);
DISPLAY INVISIBLE (3150 4725);
FORCEPROP 2 LAST PATH I179
J 0
(3425 4875);
DISPLAY 1.021277 (3425 4875);
PAINT ORANGE (3425 4875);
DISPLAY INVISIBLE (3425 4875);
FORCEADD OFFPAGE..6
(-2250 2475);
FORCEPROP 2 LAST $XR1 83 
J 0
(-2589 2475);
DISPLAY 0.638298 (-2589 2475);
PAINT MONO (-2589 2475);
FORCEPROP 2 LAST $XR0 60 
J 0
(-2499 2475);
DISPLAY 0.638298 (-2499 2475);
PAINT MONO (-2499 2475);
FORCEPROP 2 LAST CDS_LIB mstr_standard
J 0
(-2250 2475);
DISPLAY 0.787234 (-2250 2475);
PAINT MONO (-2250 2475);
DISPLAY INVISIBLE (-2250 2475);
FORCEPROP 1 LAST OFFPAGE TRUE
J 0
(-1925 2350);
DISPLAY 0.936170 (-1925 2350);
PAINT GREEN (-1925 2350);
DISPLAY INVISIBLE (-1925 2350);
FORCEPROP 1 LAST COMMENT_BODY TRUE
J 0
(-2150 2400);
DISPLAY 0.936170 (-2150 2400);
PAINT GREEN (-2150 2400);
DISPLAY INVISIBLE (-2150 2400);
FORCEPROP 2 LAST PATH I18
J 0
(-2475 2525);
DISPLAY 1.021277 (-2475 2525);
PAINT ORANGE (-2475 2525);
DISPLAY INVISIBLE (-2475 2525);
FORCEADD OFFPAGE..3
(3200 4875);
FORCEPROP 2 LAST $XR1 83 
J 0
(3504 4875);
DISPLAY 0.638298 (3504 4875);
PAINT MONO (3504 4875);
FORCEPROP 2 LAST $XR0 60 
J 0
(3414 4875);
DISPLAY 0.638298 (3414 4875);
PAINT MONO (3414 4875);
FORCEPROP 2 LAST CDS_LIB mstr_standard
J 0
(3200 4875);
DISPLAY 0.787234 (3200 4875);
PAINT MONO (3200 4875);
DISPLAY INVISIBLE (3200 4875);
FORCEPROP 1 LAST OFFPAGE TRUE
J 0
(3525 4750);
DISPLAY 0.936170 (3525 4750);
PAINT GREEN (3525 4750);
DISPLAY INVISIBLE (3525 4750);
FORCEPROP 1 LAST COMMENT_BODY TRUE
J 0
(3150 4775);
DISPLAY 0.936170 (3150 4775);
PAINT GREEN (3150 4775);
DISPLAY INVISIBLE (3150 4775);
FORCEPROP 2 LAST PATH I180
J 0
(3425 4925);
DISPLAY 1.021277 (3425 4925);
PAINT ORANGE (3425 4925);
DISPLAY INVISIBLE (3425 4925);
FORCEADD P12V_NVDIMM_KLM..1
(2150 2800);
FORCEPROP 3 LASTPIN (2150 2750) SIG_NAME P12V_NVDIMM_KLM\g
J 0
(2160 2760);
DISPLAY 0.659574 (2160 2760);
PAINT MONO (2160 2760);
DISPLAY INVISIBLE (2160 2760);
FORCEPROP 1 LAST VOLTAGE 12.0
J 0
(2105 2757);
DISPLAY 0.340426 (2105 2757);
PAINT SKYBLUE (2105 2757);
DISPLAY INVISIBLE (2105 2757);
FORCEPROP 2 LAST CDS_LIB mstr_symbols
J 0
(2150 2800);
PAINT ORANGE (2150 2800);
DISPLAY INVISIBLE (2150 2800);
FORCEPROP 1 LAST BODY_TYPE PLUMBING
J 0
(2105 2757);
DISPLAY 0.340426 (2105 2757);
PAINT GREEN (2105 2757);
DISPLAY INVISIBLE (2105 2757);
FORCEPROP 1 LAST PATH I181
J 0
(2200 2825);
DISPLAY 0.872340 (2200 2825);
PAINT AQUA (2200 2825);
DISPLAY INVISIBLE (2200 2825);
FORCEPROP 1 LAST HDL_POWER P12V_NVDIMM_KLM
J 1
(2150 2850);
DISPLAY 0.872340 (2150 2850);
PAINT GREEN (2150 2850);
DISPLAY INVISIBLE (2150 2850);
FORCEADD TAP..6
(-1600 2125);
FORCEPROP 3 LASTPIN (-1550 2125) SIG_NAME M_K_ECC<1>
J 0
(-1540 2135);
DISPLAY 0.659574 (-1540 2135);
PAINT MONO (-1540 2135);
DISPLAY INVISIBLE (-1540 2135);
FORCEPROP 1 LASTPIN (-1550 2125) BN 1
J 0
(-1600 2135);
DISPLAY 0.617021 (-1600 2135);
PAINT PINK (-1600 2135);
FORCEPROP 2 LAST CDS_LIB mstr_standard
J 0
(-1600 2125);
DISPLAY 0.787234 (-1600 2125);
PAINT MONO (-1600 2125);
DISPLAY INVISIBLE (-1600 2125);
FORCEPROP 1 LAST BODY_TYPE PLUMBING
J 0
(-1600 2075);
DISPLAY 1.234043 (-1600 2075);
PAINT GREEN (-1600 2075);
DISPLAY INVISIBLE (-1600 2075);
FORCEPROP 1 LAST HDL_TAP TRUE
J 0
(-1275 2000);
DISPLAY 1.234043 (-1275 2000);
PAINT GREEN (-1275 2000);
DISPLAY INVISIBLE (-1275 2000);
FORCEPROP 1 LAST PATH I19
J 0
(-1602 2125);
DISPLAY 0.872340 (-1602 2125);
PAINT GREEN (-1602 2125);
DISPLAY INVISIBLE (-1602 2125);
FORCEADD OFFPAGE..1
(-3150 1325);
FORCEPROP 2 LAST $XR1 83 
J 0
(-3492 1325);
DISPLAY 0.638298 (-3492 1325);
PAINT MONO (-3492 1325);
FORCEPROP 2 LAST $XR0 100 
J 0
(-3402 1325);
DISPLAY 0.638298 (-3402 1325);
PAINT MONO (-3402 1325);
FORCEPROP 2 LAST CDS_LIB mstr_standard
J 0
(-3150 1325);
DISPLAY 0.787234 (-3150 1325);
PAINT MONO (-3150 1325);
DISPLAY INVISIBLE (-3150 1325);
FORCEPROP 1 LAST OFFPAGE TRUE
J 0
(-2825 1200);
DISPLAY 0.936170 (-2825 1200);
PAINT GREEN (-2825 1200);
DISPLAY INVISIBLE (-2825 1200);
FORCEPROP 1 LAST COMMENT_BODY TRUE
J 0
(-3025 1225);
DISPLAY 0.936170 (-3025 1225);
PAINT GREEN (-3025 1225);
DISPLAY INVISIBLE (-3025 1225);
FORCEPROP 2 LAST PATH I2
J 0
(-3350 1375);
DISPLAY 1.021277 (-3350 1375);
PAINT ORANGE (-3350 1375);
DISPLAY INVISIBLE (-3350 1375);
FORCEADD TAP..6
(-1600 2075);
FORCEPROP 3 LASTPIN (-1550 2075) SIG_NAME M_K_ECC<0>
J 0
(-1540 2085);
DISPLAY 0.659574 (-1540 2085);
PAINT MONO (-1540 2085);
DISPLAY INVISIBLE (-1540 2085);
FORCEPROP 1 LASTPIN (-1550 2075) BN 0
J 0
(-1600 2085);
DISPLAY 0.617021 (-1600 2085);
PAINT PINK (-1600 2085);
FORCEPROP 2 LAST CDS_LIB mstr_standard
J 0
(-1600 2075);
DISPLAY 0.787234 (-1600 2075);
PAINT MONO (-1600 2075);
DISPLAY INVISIBLE (-1600 2075);
FORCEPROP 1 LAST BODY_TYPE PLUMBING
J 0
(-1600 2025);
DISPLAY 1.234043 (-1600 2025);
PAINT GREEN (-1600 2025);
DISPLAY INVISIBLE (-1600 2025);
FORCEPROP 1 LAST HDL_TAP TRUE
J 0
(-1275 1950);
DISPLAY 1.234043 (-1275 1950);
PAINT GREEN (-1275 1950);
DISPLAY INVISIBLE (-1275 1950);
FORCEPROP 1 LAST PATH I20
J 0
(-1602 2075);
DISPLAY 0.872340 (-1602 2075);
PAINT GREEN (-1602 2075);
DISPLAY INVISIBLE (-1602 2075);
FORCEADD TAP..6
(-1600 2175);
FORCEPROP 3 LASTPIN (-1550 2175) SIG_NAME M_K_ECC<2>
J 0
(-1540 2185);
DISPLAY 0.659574 (-1540 2185);
PAINT MONO (-1540 2185);
DISPLAY INVISIBLE (-1540 2185);
FORCEPROP 1 LASTPIN (-1550 2175) BN 2
J 0
(-1600 2185);
DISPLAY 0.617021 (-1600 2185);
PAINT PINK (-1600 2185);
FORCEPROP 2 LAST CDS_LIB mstr_standard
J 0
(-1600 2175);
DISPLAY 0.787234 (-1600 2175);
PAINT MONO (-1600 2175);
DISPLAY INVISIBLE (-1600 2175);
FORCEPROP 1 LAST BODY_TYPE PLUMBING
J 0
(-1600 2125);
DISPLAY 1.234043 (-1600 2125);
PAINT GREEN (-1600 2125);
DISPLAY INVISIBLE (-1600 2125);
FORCEPROP 1 LAST HDL_TAP TRUE
J 0
(-1275 2050);
DISPLAY 1.234043 (-1275 2050);
PAINT GREEN (-1275 2050);
DISPLAY INVISIBLE (-1275 2050);
FORCEPROP 1 LAST PATH I21
J 0
(-1602 2175);
DISPLAY 0.872340 (-1602 2175);
PAINT GREEN (-1602 2175);
DISPLAY INVISIBLE (-1602 2175);
FORCEADD TAP..6
(-1600 2225);
FORCEPROP 3 LASTPIN (-1550 2225) SIG_NAME M_K_ECC<3>
J 0
(-1540 2235);
DISPLAY 0.659574 (-1540 2235);
PAINT MONO (-1540 2235);
DISPLAY INVISIBLE (-1540 2235);
FORCEPROP 1 LASTPIN (-1550 2225) BN 3
J 0
(-1600 2235);
DISPLAY 0.617021 (-1600 2235);
PAINT PINK (-1600 2235);
FORCEPROP 2 LAST CDS_LIB mstr_standard
J 0
(-1600 2225);
DISPLAY 0.787234 (-1600 2225);
PAINT MONO (-1600 2225);
DISPLAY INVISIBLE (-1600 2225);
FORCEPROP 1 LAST BODY_TYPE PLUMBING
J 0
(-1600 2175);
DISPLAY 1.234043 (-1600 2175);
PAINT GREEN (-1600 2175);
DISPLAY INVISIBLE (-1600 2175);
FORCEPROP 1 LAST HDL_TAP TRUE
J 0
(-1275 2100);
DISPLAY 1.234043 (-1275 2100);
PAINT GREEN (-1275 2100);
DISPLAY INVISIBLE (-1275 2100);
FORCEPROP 1 LAST PATH I22
J 0
(-1602 2225);
DISPLAY 0.872340 (-1602 2225);
PAINT GREEN (-1602 2225);
DISPLAY INVISIBLE (-1602 2225);
FORCEADD TAP..6
(-1600 2275);
FORCEPROP 3 LASTPIN (-1550 2275) SIG_NAME M_K_ECC<4>
J 0
(-1540 2285);
DISPLAY 0.659574 (-1540 2285);
PAINT MONO (-1540 2285);
DISPLAY INVISIBLE (-1540 2285);
FORCEPROP 1 LASTPIN (-1550 2275) BN 4
J 0
(-1600 2285);
DISPLAY 0.617021 (-1600 2285);
PAINT PINK (-1600 2285);
FORCEPROP 2 LAST CDS_LIB mstr_standard
J 0
(-1600 2275);
DISPLAY 0.787234 (-1600 2275);
PAINT MONO (-1600 2275);
DISPLAY INVISIBLE (-1600 2275);
FORCEPROP 1 LAST BODY_TYPE PLUMBING
J 0
(-1600 2225);
DISPLAY 1.234043 (-1600 2225);
PAINT GREEN (-1600 2225);
DISPLAY INVISIBLE (-1600 2225);
FORCEPROP 1 LAST HDL_TAP TRUE
J 0
(-1275 2150);
DISPLAY 1.234043 (-1275 2150);
PAINT GREEN (-1275 2150);
DISPLAY INVISIBLE (-1275 2150);
FORCEPROP 1 LAST PATH I23
J 0
(-1602 2275);
DISPLAY 0.872340 (-1602 2275);
PAINT GREEN (-1602 2275);
DISPLAY INVISIBLE (-1602 2275);
FORCEADD TAP..6
(-1600 2375);
FORCEPROP 3 LASTPIN (-1550 2375) SIG_NAME M_K_ECC<6>
J 0
(-1540 2385);
DISPLAY 0.659574 (-1540 2385);
PAINT MONO (-1540 2385);
DISPLAY INVISIBLE (-1540 2385);
FORCEPROP 1 LASTPIN (-1550 2375) BN 6
J 0
(-1600 2385);
DISPLAY 0.617021 (-1600 2385);
PAINT PINK (-1600 2385);
FORCEPROP 2 LAST CDS_LIB mstr_standard
J 0
(-1600 2375);
DISPLAY 0.787234 (-1600 2375);
PAINT MONO (-1600 2375);
DISPLAY INVISIBLE (-1600 2375);
FORCEPROP 1 LAST BODY_TYPE PLUMBING
J 0
(-1600 2325);
DISPLAY 1.234043 (-1600 2325);
PAINT GREEN (-1600 2325);
DISPLAY INVISIBLE (-1600 2325);
FORCEPROP 1 LAST HDL_TAP TRUE
J 0
(-1275 2250);
DISPLAY 1.234043 (-1275 2250);
PAINT GREEN (-1275 2250);
DISPLAY INVISIBLE (-1275 2250);
FORCEPROP 1 LAST PATH I24
J 0
(-1602 2375);
DISPLAY 0.872340 (-1602 2375);
PAINT GREEN (-1602 2375);
DISPLAY INVISIBLE (-1602 2375);
FORCEADD TAP..6
(-1600 2325);
FORCEPROP 3 LASTPIN (-1550 2325) SIG_NAME M_K_ECC<5>
J 0
(-1540 2335);
DISPLAY 0.659574 (-1540 2335);
PAINT MONO (-1540 2335);
DISPLAY INVISIBLE (-1540 2335);
FORCEPROP 1 LASTPIN (-1550 2325) BN 5
J 0
(-1600 2335);
DISPLAY 0.617021 (-1600 2335);
PAINT PINK (-1600 2335);
FORCEPROP 2 LAST CDS_LIB mstr_standard
J 0
(-1600 2325);
DISPLAY 0.787234 (-1600 2325);
PAINT MONO (-1600 2325);
DISPLAY INVISIBLE (-1600 2325);
FORCEPROP 1 LAST BODY_TYPE PLUMBING
J 0
(-1600 2275);
DISPLAY 1.234043 (-1600 2275);
PAINT GREEN (-1600 2275);
DISPLAY INVISIBLE (-1600 2275);
FORCEPROP 1 LAST HDL_TAP TRUE
J 0
(-1275 2200);
DISPLAY 1.234043 (-1275 2200);
PAINT GREEN (-1275 2200);
DISPLAY INVISIBLE (-1275 2200);
FORCEPROP 1 LAST PATH I25
J 0
(-1602 2325);
DISPLAY 0.872340 (-1602 2325);
PAINT GREEN (-1602 2325);
DISPLAY INVISIBLE (-1602 2325);
FORCEADD TAP..6
(-1600 2425);
FORCEPROP 3 LASTPIN (-1550 2425) SIG_NAME M_K_ECC<7>
J 0
(-1540 2435);
DISPLAY 0.659574 (-1540 2435);
PAINT MONO (-1540 2435);
DISPLAY INVISIBLE (-1540 2435);
FORCEPROP 1 LASTPIN (-1550 2425) BN 7
J 0
(-1600 2435);
DISPLAY 0.617021 (-1600 2435);
PAINT PINK (-1600 2435);
FORCEPROP 2 LAST CDS_LIB mstr_standard
J 0
(-1600 2425);
DISPLAY 0.787234 (-1600 2425);
PAINT MONO (-1600 2425);
DISPLAY INVISIBLE (-1600 2425);
FORCEPROP 1 LAST BODY_TYPE PLUMBING
J 0
(-1600 2375);
DISPLAY 1.234043 (-1600 2375);
PAINT GREEN (-1600 2375);
DISPLAY INVISIBLE (-1600 2375);
FORCEPROP 1 LAST HDL_TAP TRUE
J 0
(-1275 2300);
DISPLAY 1.234043 (-1275 2300);
PAINT GREEN (-1275 2300);
DISPLAY INVISIBLE (-1275 2300);
FORCEPROP 1 LAST PATH I26
J 0
(-1602 2425);
DISPLAY 0.872340 (-1602 2425);
PAINT GREEN (-1602 2425);
DISPLAY INVISIBLE (-1602 2425);
FORCEADD TAP..6
(-1600 2525);
FORCEPROP 3 LASTPIN (-1550 2525) SIG_NAME M_K_ODT<2>
J 0
(-1540 2535);
DISPLAY 0.659574 (-1540 2535);
PAINT MONO (-1540 2535);
DISPLAY INVISIBLE (-1540 2535);
FORCEPROP 1 LASTPIN (-1550 2525) BN 2
J 0
(-1600 2535);
DISPLAY 0.617021 (-1600 2535);
PAINT PINK (-1600 2535);
FORCEPROP 2 LAST CDS_LIB mstr_standard
J 0
(-1600 2525);
DISPLAY 0.787234 (-1600 2525);
PAINT MONO (-1600 2525);
DISPLAY INVISIBLE (-1600 2525);
FORCEPROP 1 LAST BODY_TYPE PLUMBING
J 0
(-1600 2475);
DISPLAY 1.234043 (-1600 2475);
PAINT GREEN (-1600 2475);
DISPLAY INVISIBLE (-1600 2475);
FORCEPROP 1 LAST HDL_TAP TRUE
J 0
(-1275 2400);
DISPLAY 1.234043 (-1275 2400);
PAINT GREEN (-1275 2400);
DISPLAY INVISIBLE (-1275 2400);
FORCEPROP 1 LAST PATH I27
J 0
(-1602 2525);
DISPLAY 0.872340 (-1602 2525);
PAINT GREEN (-1602 2525);
DISPLAY INVISIBLE (-1602 2525);
FORCEADD TAP..6
(-1600 2575);
FORCEPROP 3 LASTPIN (-1550 2575) SIG_NAME M_K_ODT<3>
J 0
(-1540 2585);
DISPLAY 0.659574 (-1540 2585);
PAINT MONO (-1540 2585);
DISPLAY INVISIBLE (-1540 2585);
FORCEPROP 1 LASTPIN (-1550 2575) BN 3
J 0
(-1600 2585);
DISPLAY 0.617021 (-1600 2585);
PAINT PINK (-1600 2585);
FORCEPROP 2 LAST CDS_LIB mstr_standard
J 0
(-1600 2575);
DISPLAY 0.787234 (-1600 2575);
PAINT MONO (-1600 2575);
DISPLAY INVISIBLE (-1600 2575);
FORCEPROP 1 LAST BODY_TYPE PLUMBING
J 0
(-1600 2525);
DISPLAY 1.234043 (-1600 2525);
PAINT GREEN (-1600 2525);
DISPLAY INVISIBLE (-1600 2525);
FORCEPROP 1 LAST HDL_TAP TRUE
J 0
(-1275 2450);
DISPLAY 1.234043 (-1275 2450);
PAINT GREEN (-1275 2450);
DISPLAY INVISIBLE (-1275 2450);
FORCEPROP 1 LAST PATH I28
J 0
(-1602 2575);
DISPLAY 0.872340 (-1602 2575);
PAINT GREEN (-1602 2575);
DISPLAY INVISIBLE (-1602 2575);
FORCEADD TAP..6
(-1600 2675);
FORCEPROP 3 LASTPIN (-1550 2675) SIG_NAME M_K_CKE<2>
J 0
(-1540 2685);
DISPLAY 0.659574 (-1540 2685);
PAINT MONO (-1540 2685);
DISPLAY INVISIBLE (-1540 2685);
FORCEPROP 1 LASTPIN (-1550 2675) BN 2
J 0
(-1600 2685);
DISPLAY 0.617021 (-1600 2685);
PAINT PINK (-1600 2685);
FORCEPROP 2 LAST CDS_LIB mstr_standard
J 0
(-1600 2675);
DISPLAY 0.787234 (-1600 2675);
PAINT MONO (-1600 2675);
DISPLAY INVISIBLE (-1600 2675);
FORCEPROP 1 LAST BODY_TYPE PLUMBING
J 0
(-1600 2625);
DISPLAY 1.234043 (-1600 2625);
PAINT GREEN (-1600 2625);
DISPLAY INVISIBLE (-1600 2625);
FORCEPROP 1 LAST HDL_TAP TRUE
J 0
(-1275 2550);
DISPLAY 1.234043 (-1275 2550);
PAINT GREEN (-1275 2550);
DISPLAY INVISIBLE (-1275 2550);
FORCEPROP 1 LAST PATH I29
J 0
(-1602 2675);
DISPLAY 0.872340 (-1602 2675);
PAINT GREEN (-1602 2675);
DISPLAY INVISIBLE (-1602 2675);
FORCEADD GND..1
(-3000 875);
FORCEPROP 3 LASTPIN (-3000 925) SIG_NAME GND\g
J 0
(-2990 935);
DISPLAY 0.659574 (-2990 935);
PAINT MONO (-2990 935);
DISPLAY INVISIBLE (-2990 935);
FORCEPROP 1 LAST VOLTAGE 0
J 0
(-3000 875);
PAINT SKYBLUE (-3000 875);
DISPLAY INVISIBLE (-3000 875);
FORCEPROP 2 LAST CDS_LIB mstr_symbols
J 0
(-3000 875);
PAINT ORANGE (-3000 875);
DISPLAY INVISIBLE (-3000 875);
FORCEPROP 1 LAST SIZE 1B
J 0
(-2925 825);
DISPLAY 1.787234 (-2925 825);
PAINT GREEN (-2925 825);
DISPLAY INVISIBLE (-2925 825);
FORCEPROP 2 LAST BOM_COST MEM
J 0
(-3000 880);
PAINT ORANGE (-3000 880);
DISPLAY INVISIBLE (-3000 880);
FORCEPROP 1 LAST BODY_TYPE PLUMBING
J 0
(-3045 832);
DISPLAY 0.340426 (-3045 832);
PAINT GREEN (-3045 832);
DISPLAY INVISIBLE (-3045 832);
FORCEPROP 1 LAST PATH I3
J 0
(-2925 875);
DISPLAY 0.872340 (-2925 875);
PAINT AQUA (-2925 875);
DISPLAY INVISIBLE (-2925 875);
FORCEPROP 2 LAST ROOM DDR4_CH_C
J 0
(-3000 880);
PAINT ORANGE (-3000 880);
DISPLAY INVISIBLE (-3000 880);
FORCEPROP 1 LAST HDL_POWER GND
J 0
(-3000 1025);
DISPLAY 1.404255 (-3000 1025);
PAINT GREEN (-3000 1025);
DISPLAY INVISIBLE (-3000 1025);
FORCEADD OFFPAGE..1
(-2250 2775);
FORCEPROP 2 LAST $XR1 83 
J 0
(-2591 2775);
DISPLAY 0.638298 (-2591 2775);
PAINT MONO (-2591 2775);
FORCEPROP 2 LAST $XR0 60 
J 0
(-2501 2775);
DISPLAY 0.638298 (-2501 2775);
PAINT MONO (-2501 2775);
FORCEPROP 2 LAST CDS_LIB mstr_standard
J 0
(-2250 2775);
DISPLAY 0.787234 (-2250 2775);
PAINT MONO (-2250 2775);
DISPLAY INVISIBLE (-2250 2775);
FORCEPROP 1 LAST OFFPAGE TRUE
J 0
(-1925 2650);
DISPLAY 0.936170 (-1925 2650);
PAINT GREEN (-1925 2650);
DISPLAY INVISIBLE (-1925 2650);
FORCEPROP 1 LAST COMMENT_BODY TRUE
J 0
(-2125 2675);
DISPLAY 0.936170 (-2125 2675);
PAINT GREEN (-2125 2675);
DISPLAY INVISIBLE (-2125 2675);
FORCEPROP 2 LAST PATH I30
J 0
(-2500 2825);
DISPLAY 1.021277 (-2500 2825);
PAINT ORANGE (-2500 2825);
DISPLAY INVISIBLE (-2500 2825);
FORCEADD OFFPAGE..1
(-2250 3025);
FORCEPROP 2 LAST $XR1 83 
J 0
(-2591 3025);
DISPLAY 0.638298 (-2591 3025);
PAINT MONO (-2591 3025);
FORCEPROP 2 LAST $XR0 60 
J 0
(-2501 3025);
DISPLAY 0.638298 (-2501 3025);
PAINT MONO (-2501 3025);
FORCEPROP 2 LAST CDS_LIB mstr_standard
J 0
(-2250 3025);
DISPLAY 0.787234 (-2250 3025);
PAINT MONO (-2250 3025);
DISPLAY INVISIBLE (-2250 3025);
FORCEPROP 1 LAST OFFPAGE TRUE
J 0
(-1925 2900);
DISPLAY 0.936170 (-1925 2900);
PAINT GREEN (-1925 2900);
DISPLAY INVISIBLE (-1925 2900);
FORCEPROP 1 LAST COMMENT_BODY TRUE
J 0
(-2125 2925);
DISPLAY 0.936170 (-2125 2925);
PAINT GREEN (-2125 2925);
DISPLAY INVISIBLE (-2125 2925);
FORCEPROP 2 LAST PATH I31
J 0
(-2500 3075);
DISPLAY 1.021277 (-2500 3075);
PAINT ORANGE (-2500 3075);
DISPLAY INVISIBLE (-2500 3075);
FORCEADD OFFPAGE..1
(-2250 3075);
FORCEPROP 2 LAST $XR1 83 
J 0
(-2591 3075);
DISPLAY 0.638298 (-2591 3075);
PAINT MONO (-2591 3075);
FORCEPROP 2 LAST $XR0 60 
J 0
(-2501 3075);
DISPLAY 0.638298 (-2501 3075);
PAINT MONO (-2501 3075);
FORCEPROP 2 LAST CDS_LIB mstr_standard
J 0
(-2250 3075);
DISPLAY 0.787234 (-2250 3075);
PAINT MONO (-2250 3075);
DISPLAY INVISIBLE (-2250 3075);
FORCEPROP 1 LAST OFFPAGE TRUE
J 0
(-1925 2950);
DISPLAY 0.936170 (-1925 2950);
PAINT GREEN (-1925 2950);
DISPLAY INVISIBLE (-1925 2950);
FORCEPROP 1 LAST COMMENT_BODY TRUE
J 0
(-2125 2975);
DISPLAY 0.936170 (-2125 2975);
PAINT GREEN (-2125 2975);
DISPLAY INVISIBLE (-2125 2975);
FORCEPROP 2 LAST PATH I32
J 0
(-2500 3125);
DISPLAY 1.021277 (-2500 3125);
PAINT ORANGE (-2500 3125);
DISPLAY INVISIBLE (-2500 3125);
FORCEADD TAP..6
(-2100 3125);
FORCEPROP 3 LASTPIN (-2050 3125) SIG_NAME M_K_CLK_DN<2>
J 0
(-2040 3135);
DISPLAY 0.659574 (-2040 3135);
PAINT MONO (-2040 3135);
DISPLAY INVISIBLE (-2040 3135);
FORCEPROP 1 LASTPIN (-2050 3125) BN 2
J 0
(-2100 3135);
DISPLAY 0.617021 (-2100 3135);
PAINT PINK (-2100 3135);
FORCEPROP 2 LAST CDS_LIB mstr_standard
J 0
(-2100 3125);
DISPLAY 0.787234 (-2100 3125);
PAINT MONO (-2100 3125);
DISPLAY INVISIBLE (-2100 3125);
FORCEPROP 1 LAST BODY_TYPE PLUMBING
J 0
(-2100 3075);
DISPLAY 1.234043 (-2100 3075);
PAINT GREEN (-2100 3075);
DISPLAY INVISIBLE (-2100 3075);
FORCEPROP 1 LAST HDL_TAP TRUE
J 0
(-1775 3000);
DISPLAY 1.234043 (-1775 3000);
PAINT GREEN (-1775 3000);
DISPLAY INVISIBLE (-1775 3000);
FORCEPROP 1 LAST PATH I33
J 0
(-2102 3125);
DISPLAY 0.872340 (-2102 3125);
PAINT GREEN (-2102 3125);
DISPLAY INVISIBLE (-2102 3125);
FORCEADD TAP..6
(-1950 3175);
FORCEPROP 3 LASTPIN (-1900 3175) SIG_NAME M_K_CLK_DP<2>
J 0
(-1890 3185);
DISPLAY 0.659574 (-1890 3185);
PAINT MONO (-1890 3185);
DISPLAY INVISIBLE (-1890 3185);
FORCEPROP 1 LASTPIN (-1900 3175) BN 2
J 0
(-1950 3185);
DISPLAY 0.617021 (-1950 3185);
PAINT PINK (-1950 3185);
FORCEPROP 2 LAST CDS_LIB mstr_standard
J 0
(-1950 3175);
DISPLAY 0.787234 (-1950 3175);
PAINT MONO (-1950 3175);
DISPLAY INVISIBLE (-1950 3175);
FORCEPROP 1 LAST BODY_TYPE PLUMBING
J 0
(-1950 3125);
DISPLAY 1.234043 (-1950 3125);
PAINT GREEN (-1950 3125);
DISPLAY INVISIBLE (-1950 3125);
FORCEPROP 1 LAST HDL_TAP TRUE
J 0
(-1625 3050);
DISPLAY 1.234043 (-1625 3050);
PAINT GREEN (-1625 3050);
DISPLAY INVISIBLE (-1625 3050);
FORCEPROP 1 LAST PATH I34
J 0
(-1952 3175);
DISPLAY 0.872340 (-1952 3175);
PAINT GREEN (-1952 3175);
DISPLAY INVISIBLE (-1952 3175);
FORCEADD OFFPAGE..1
(-2250 3475);
FORCEPROP 2 LAST $XR1 83 
J 0
(-2591 3475);
DISPLAY 0.638298 (-2591 3475);
PAINT MONO (-2591 3475);
FORCEPROP 2 LAST $XR0 60 
J 0
(-2501 3475);
DISPLAY 0.638298 (-2501 3475);
PAINT MONO (-2501 3475);
FORCEPROP 2 LAST CDS_LIB mstr_standard
J 0
(-2250 3475);
DISPLAY 0.787234 (-2250 3475);
PAINT MONO (-2250 3475);
DISPLAY INVISIBLE (-2250 3475);
FORCEPROP 1 LAST OFFPAGE TRUE
J 0
(-1925 3350);
DISPLAY 0.936170 (-1925 3350);
PAINT GREEN (-1925 3350);
DISPLAY INVISIBLE (-1925 3350);
FORCEPROP 1 LAST COMMENT_BODY TRUE
J 0
(-2125 3375);
DISPLAY 0.936170 (-2125 3375);
PAINT GREEN (-2125 3375);
DISPLAY INVISIBLE (-2125 3375);
FORCEPROP 2 LAST PATH I35
J 0
(-2500 3525);
DISPLAY 1.021277 (-2500 3525);
PAINT ORANGE (-2500 3525);
DISPLAY INVISIBLE (-2500 3525);
FORCEADD OFFPAGE..1
(-2250 3575);
FORCEPROP 2 LAST $XR1 83 
J 0
(-2591 3575);
DISPLAY 0.638298 (-2591 3575);
PAINT MONO (-2591 3575);
FORCEPROP 2 LAST $XR0 60 
J 0
(-2501 3575);
DISPLAY 0.638298 (-2501 3575);
PAINT MONO (-2501 3575);
FORCEPROP 2 LAST CDS_LIB mstr_standard
J 0
(-2250 3575);
DISPLAY 0.787234 (-2250 3575);
PAINT MONO (-2250 3575);
DISPLAY INVISIBLE (-2250 3575);
FORCEPROP 1 LAST OFFPAGE TRUE
J 0
(-1925 3450);
DISPLAY 0.936170 (-1925 3450);
PAINT GREEN (-1925 3450);
DISPLAY INVISIBLE (-1925 3450);
FORCEPROP 1 LAST COMMENT_BODY TRUE
J 0
(-2125 3475);
DISPLAY 0.936170 (-2125 3475);
PAINT GREEN (-2125 3475);
DISPLAY INVISIBLE (-2125 3475);
FORCEPROP 2 LAST PATH I36
J 0
(-2500 3625);
DISPLAY 1.021277 (-2500 3625);
PAINT ORANGE (-2500 3625);
DISPLAY INVISIBLE (-2500 3625);
FORCEADD TAP..6
(-2100 3225);
FORCEPROP 3 LASTPIN (-2050 3225) SIG_NAME M_K_CLK_DN<3>
J 0
(-2040 3235);
DISPLAY 0.659574 (-2040 3235);
PAINT MONO (-2040 3235);
DISPLAY INVISIBLE (-2040 3235);
FORCEPROP 1 LASTPIN (-2050 3225) BN 3
J 0
(-2102 3233);
DISPLAY 0.617021 (-2102 3233);
PAINT PINK (-2102 3233);
FORCEPROP 2 LAST CDS_LIB mstr_standard
J 0
(-2100 3225);
PAINT MONO (-2100 3225);
DISPLAY INVISIBLE (-2100 3225);
FORCEPROP 1 LAST BODY_TYPE PLUMBING
J 0
(-2100 3175);
DISPLAY 1.234043 (-2100 3175);
PAINT GREEN (-2100 3175);
DISPLAY INVISIBLE (-2100 3175);
FORCEPROP 1 LAST HDL_TAP TRUE
J 0
(-1775 3100);
DISPLAY 1.234043 (-1775 3100);
PAINT GREEN (-1775 3100);
DISPLAY INVISIBLE (-1775 3100);
FORCEPROP 1 LAST PATH I37
J 0
(-2102 3225);
DISPLAY 0.872340 (-2102 3225);
PAINT GREEN (-2102 3225);
DISPLAY INVISIBLE (-2102 3225);
FORCEADD TAP..6
(-1950 3275);
FORCEPROP 3 LASTPIN (-1900 3275) SIG_NAME M_K_CLK_DP<3>
J 0
(-1890 3285);
DISPLAY 0.659574 (-1890 3285);
PAINT MONO (-1890 3285);
DISPLAY INVISIBLE (-1890 3285);
FORCEPROP 1 LASTPIN (-1900 3275) BN 3
J 0
(-1952 3283);
DISPLAY 0.617021 (-1952 3283);
PAINT PINK (-1952 3283);
FORCEPROP 2 LAST CDS_LIB mstr_standard
J 0
(-1950 3275);
PAINT MONO (-1950 3275);
DISPLAY INVISIBLE (-1950 3275);
FORCEPROP 1 LAST BODY_TYPE PLUMBING
J 0
(-1950 3225);
DISPLAY 1.234043 (-1950 3225);
PAINT GREEN (-1950 3225);
DISPLAY INVISIBLE (-1950 3225);
FORCEPROP 1 LAST HDL_TAP TRUE
J 0
(-1625 3150);
DISPLAY 1.234043 (-1625 3150);
PAINT GREEN (-1625 3150);
DISPLAY INVISIBLE (-1625 3150);
FORCEPROP 1 LAST PATH I38
J 0
(-1952 3275);
DISPLAY 0.872340 (-1952 3275);
PAINT GREEN (-1952 3275);
DISPLAY INVISIBLE (-1952 3275);
FORCEADD TAP..6
(-1600 2725);
FORCEPROP 3 LASTPIN (-1550 2725) SIG_NAME M_K_CKE<3>
J 0
(-1540 2735);
DISPLAY 0.659574 (-1540 2735);
PAINT MONO (-1540 2735);
DISPLAY INVISIBLE (-1540 2735);
FORCEPROP 1 LASTPIN (-1550 2725) BN 3
J 0
(-1600 2735);
DISPLAY 0.617021 (-1600 2735);
PAINT PINK (-1600 2735);
FORCEPROP 2 LAST CDS_LIB mstr_standard
J 0
(-1600 2725);
DISPLAY 0.787234 (-1600 2725);
PAINT MONO (-1600 2725);
DISPLAY INVISIBLE (-1600 2725);
FORCEPROP 1 LAST BODY_TYPE PLUMBING
J 0
(-1600 2675);
DISPLAY 1.234043 (-1600 2675);
PAINT GREEN (-1600 2675);
DISPLAY INVISIBLE (-1600 2675);
FORCEPROP 1 LAST HDL_TAP TRUE
J 0
(-1275 2600);
DISPLAY 1.234043 (-1275 2600);
PAINT GREEN (-1275 2600);
DISPLAY INVISIBLE (-1275 2600);
FORCEPROP 1 LAST PATH I39
J 0
(-1602 2725);
DISPLAY 0.872340 (-1602 2725);
PAINT GREEN (-1602 2725);
DISPLAY INVISIBLE (-1602 2725);
FORCEADD CAP_A..1
R 2
(-3000 1125);
FORCEPROP 1 LAST LOCATION C9M1
J 2
(-3050 1225);
DISPLAY 0.617021 (-3050 1225);
PAINT AQUA (-3050 1225);
FORCEPROP 1 LAST PART_NUMBER A36096-045
J 2
(-3050 975);
DISPLAY 0.617021 (-3050 975);
PAINT BLUE (-3050 975);
FORCEPROP 1 LAST VALUE 0.01UF
J 2
(-3050 1175);
DISPLAY 0.617021 (-3050 1175);
PAINT SKYBLUE (-3050 1175);
FORCEPROP 1 LAST TOLERANCE 10%
J 2
(-3050 1075);
DISPLAY 0.617021 (-3050 1075);
PAINT SKYBLUE (-3050 1075);
FORCEPROP 1 LAST PACK_TYPE 0402V
J 2
(-3050 925);
DISPLAY 0.617021 (-3050 925);
PAINT SKYBLUE (-3050 925);
FORCEPROP 1 LAST VOLTAGE 25V
J 2
(-3050 1125);
DISPLAY 0.617021 (-3050 1125);
PAINT SKYBLUE (-3050 1125);
FORCEPROP 1 LAST MATERIAL X7R
J 2
(-3050 1025);
DISPLAY 0.617021 (-3050 1025);
PAINT SKYBLUE (-3050 1025);
FORCEPROP 2 LAST CDS_LOCATION C9M1
J 2
(-3050 1225);
DISPLAY 0.617021 (-3050 1225);
PAINT AQUA (-3050 1225);
DISPLAY INVISIBLE (-3050 1225);
FORCEPROP 2 LAST BOM_COST MEM
J 0
(-3000 1125);
PAINT ORANGE (-3000 1125);
DISPLAY INVISIBLE (-3000 1125);
FORCEPROP 2 LAST CDS_LIB dev_discrete
J 0
(-3000 1125);
PAINT ORANGE (-3000 1125);
DISPLAY INVISIBLE (-3000 1125);
FORCEPROP 2 LAST CDS_SEC 1
J 0
(-3050 1325);
PAINT MONO (-3050 1325);
DISPLAY INVISIBLE (-3050 1325);
FORCEPROP 2 LAST $SEC 1
J 0
(-3050 1325);
PAINT MONO (-3050 1325);
DISPLAY INVISIBLE (-3050 1325);
FORCEPROP 1 LAST PATH I4
J 2
(-3050 1275);
DISPLAY 0.978723 (-3050 1275);
PAINT WHITE (-3050 1275);
DISPLAY INVISIBLE (-3050 1275);
FORCEPROP 2 LAST ROOM DDR4_CH_C
J 0
(-3000 1125);
PAINT ORANGE (-3000 1125);
DISPLAY INVISIBLE (-3000 1125);
FORCEPROP 1 LASTPIN (-3000 1225) $PN 1
J 2
(-3010 1205);
DISPLAY 0.787234 (-3010 1205);
PAINT ORANGE (-3010 1205);
DISPLAY INVISIBLE (-3010 1205);
FORCEPROP 1 LASTPIN (-3000 1025) $PN 2
J 2
(-3010 1005);
DISPLAY 0.787234 (-3010 1005);
PAINT ORANGE (-3010 1005);
DISPLAY INVISIBLE (-3010 1005);
FORCEADD TAP..6
(-1600 2925);
FORCEPROP 3 LASTPIN (-1550 2925) SIG_NAME M_K_CS_N<6>
J 0
(-1540 2935);
DISPLAY 0.659574 (-1540 2935);
PAINT MONO (-1540 2935);
DISPLAY INVISIBLE (-1540 2935);
FORCEPROP 1 LASTPIN (-1550 2925) BN 6
J 0
(-1600 2935);
DISPLAY 0.617021 (-1600 2935);
PAINT PINK (-1600 2935);
FORCEPROP 2 LAST CDS_LIB mstr_standard
J 0
(-1600 2925);
DISPLAY 0.787234 (-1600 2925);
PAINT MONO (-1600 2925);
DISPLAY INVISIBLE (-1600 2925);
FORCEPROP 1 LAST BODY_TYPE PLUMBING
J 0
(-1600 2875);
DISPLAY 1.234043 (-1600 2875);
PAINT GREEN (-1600 2875);
DISPLAY INVISIBLE (-1600 2875);
FORCEPROP 1 LAST HDL_TAP TRUE
J 0
(-1275 2800);
DISPLAY 1.234043 (-1275 2800);
PAINT GREEN (-1275 2800);
DISPLAY INVISIBLE (-1275 2800);
FORCEPROP 1 LAST PATH I40
J 0
(-1602 2925);
DISPLAY 0.872340 (-1602 2925);
PAINT GREEN (-1602 2925);
DISPLAY INVISIBLE (-1602 2925);
FORCEADD TAP..6
(-1600 2875);
FORCEPROP 3 LASTPIN (-1550 2875) SIG_NAME M_K_CS_N<5>
J 0
(-1540 2885);
DISPLAY 0.659574 (-1540 2885);
PAINT MONO (-1540 2885);
DISPLAY INVISIBLE (-1540 2885);
FORCEPROP 1 LASTPIN (-1550 2875) BN 5
J 0
(-1600 2885);
DISPLAY 0.617021 (-1600 2885);
PAINT PINK (-1600 2885);
FORCEPROP 2 LAST CDS_LIB mstr_standard
J 0
(-1600 2875);
DISPLAY 0.787234 (-1600 2875);
PAINT MONO (-1600 2875);
DISPLAY INVISIBLE (-1600 2875);
FORCEPROP 1 LAST BODY_TYPE PLUMBING
J 0
(-1600 2825);
DISPLAY 1.234043 (-1600 2825);
PAINT GREEN (-1600 2825);
DISPLAY INVISIBLE (-1600 2825);
FORCEPROP 1 LAST HDL_TAP TRUE
J 0
(-1275 2750);
DISPLAY 1.234043 (-1275 2750);
PAINT GREEN (-1275 2750);
DISPLAY INVISIBLE (-1275 2750);
FORCEPROP 1 LAST PATH I41
J 0
(-1602 2875);
DISPLAY 0.872340 (-1602 2875);
PAINT GREEN (-1602 2875);
DISPLAY INVISIBLE (-1602 2875);
FORCEADD TAP..6
(-1600 2825);
FORCEPROP 3 LASTPIN (-1550 2825) SIG_NAME M_K_CS_N<4>
J 0
(-1540 2835);
DISPLAY 0.659574 (-1540 2835);
PAINT MONO (-1540 2835);
DISPLAY INVISIBLE (-1540 2835);
FORCEPROP 1 LASTPIN (-1550 2825) BN 4
J 0
(-1600 2835);
DISPLAY 0.617021 (-1600 2835);
PAINT PINK (-1600 2835);
FORCEPROP 2 LAST CDS_LIB mstr_standard
J 0
(-1600 2825);
DISPLAY 0.787234 (-1600 2825);
PAINT MONO (-1600 2825);
DISPLAY INVISIBLE (-1600 2825);
FORCEPROP 1 LAST BODY_TYPE PLUMBING
J 0
(-1600 2775);
DISPLAY 1.234043 (-1600 2775);
PAINT GREEN (-1600 2775);
DISPLAY INVISIBLE (-1600 2775);
FORCEPROP 1 LAST HDL_TAP TRUE
J 0
(-1275 2700);
DISPLAY 1.234043 (-1275 2700);
PAINT GREEN (-1275 2700);
DISPLAY INVISIBLE (-1275 2700);
FORCEPROP 1 LAST PATH I42
J 0
(-1602 2825);
DISPLAY 0.872340 (-1602 2825);
PAINT GREEN (-1602 2825);
DISPLAY INVISIBLE (-1602 2825);
FORCEADD TAP..6
(-1600 2975);
FORCEPROP 3 LASTPIN (-1550 2975) SIG_NAME M_K_CS_N<7>
J 0
(-1540 2985);
DISPLAY 0.659574 (-1540 2985);
PAINT MONO (-1540 2985);
DISPLAY INVISIBLE (-1540 2985);
FORCEPROP 1 LASTPIN (-1550 2975) BN 7
J 0
(-1600 2985);
DISPLAY 0.617021 (-1600 2985);
PAINT PINK (-1600 2985);
FORCEPROP 2 LAST CDS_LIB mstr_standard
J 0
(-1600 2975);
DISPLAY 0.787234 (-1600 2975);
PAINT MONO (-1600 2975);
DISPLAY INVISIBLE (-1600 2975);
FORCEPROP 1 LAST BODY_TYPE PLUMBING
J 0
(-1600 2925);
DISPLAY 1.234043 (-1600 2925);
PAINT GREEN (-1600 2925);
DISPLAY INVISIBLE (-1600 2925);
FORCEPROP 1 LAST HDL_TAP TRUE
J 0
(-1275 2850);
DISPLAY 1.234043 (-1275 2850);
PAINT GREEN (-1275 2850);
DISPLAY INVISIBLE (-1275 2850);
FORCEPROP 1 LAST PATH I43
J 0
(-1602 2975);
DISPLAY 0.872340 (-1602 2975);
PAINT GREEN (-1602 2975);
DISPLAY INVISIBLE (-1602 2975);
FORCEADD TAP..6
(-1600 3425);
FORCEPROP 3 LASTPIN (-1550 3425) SIG_NAME M_K_BG<1>
J 0
(-1540 3435);
DISPLAY 0.659574 (-1540 3435);
PAINT MONO (-1540 3435);
DISPLAY INVISIBLE (-1540 3435);
FORCEPROP 1 LASTPIN (-1550 3425) BN 1
J 0
(-1600 3435);
DISPLAY 0.617021 (-1600 3435);
PAINT PINK (-1600 3435);
FORCEPROP 2 LAST CDS_LIB mstr_standard
J 0
(-1600 3425);
DISPLAY 0.787234 (-1600 3425);
PAINT MONO (-1600 3425);
DISPLAY INVISIBLE (-1600 3425);
FORCEPROP 1 LAST BODY_TYPE PLUMBING
J 0
(-1600 3375);
DISPLAY 1.234043 (-1600 3375);
PAINT GREEN (-1600 3375);
DISPLAY INVISIBLE (-1600 3375);
FORCEPROP 1 LAST HDL_TAP TRUE
J 0
(-1275 3300);
DISPLAY 1.234043 (-1275 3300);
PAINT GREEN (-1275 3300);
DISPLAY INVISIBLE (-1275 3300);
FORCEPROP 1 LAST PATH I44
J 0
(-1602 3425);
DISPLAY 0.872340 (-1602 3425);
PAINT GREEN (-1602 3425);
DISPLAY INVISIBLE (-1602 3425);
FORCEADD TAP..6
(-1600 3375);
FORCEPROP 3 LASTPIN (-1550 3375) SIG_NAME M_K_BG<0>
J 0
(-1540 3385);
DISPLAY 0.659574 (-1540 3385);
PAINT MONO (-1540 3385);
DISPLAY INVISIBLE (-1540 3385);
FORCEPROP 1 LASTPIN (-1550 3375) BN 0
J 0
(-1600 3385);
DISPLAY 0.617021 (-1600 3385);
PAINT PINK (-1600 3385);
FORCEPROP 2 LAST CDS_LIB mstr_standard
J 0
(-1600 3375);
DISPLAY 0.787234 (-1600 3375);
PAINT MONO (-1600 3375);
DISPLAY INVISIBLE (-1600 3375);
FORCEPROP 1 LAST BODY_TYPE PLUMBING
J 0
(-1600 3325);
DISPLAY 1.234043 (-1600 3325);
PAINT GREEN (-1600 3325);
DISPLAY INVISIBLE (-1600 3325);
FORCEPROP 1 LAST HDL_TAP TRUE
J 0
(-1275 3250);
DISPLAY 1.234043 (-1275 3250);
PAINT GREEN (-1275 3250);
DISPLAY INVISIBLE (-1275 3250);
FORCEPROP 1 LAST PATH I45
J 0
(-1602 3375);
DISPLAY 0.872340 (-1602 3375);
PAINT GREEN (-1602 3375);
DISPLAY INVISIBLE (-1602 3375);
FORCEADD TAP..6
(-1600 3675);
FORCEPROP 3 LASTPIN (-1550 3675) SIG_NAME M_K_MA<1>
J 0
(-1540 3685);
DISPLAY 0.659574 (-1540 3685);
PAINT MONO (-1540 3685);
DISPLAY INVISIBLE (-1540 3685);
FORCEPROP 1 LASTPIN (-1550 3675) BN 1
J 0
(-1600 3685);
DISPLAY 0.617021 (-1600 3685);
PAINT PINK (-1600 3685);
FORCEPROP 2 LAST CDS_LIB mstr_standard
J 2
(-1600 3675);
DISPLAY 0.787234 (-1600 3675);
PAINT MONO (-1600 3675);
DISPLAY INVISIBLE (-1600 3675);
FORCEPROP 1 LAST BODY_TYPE PLUMBING
J 0
(-1600 3625);
DISPLAY 1.234043 (-1600 3625);
PAINT GREEN (-1600 3625);
DISPLAY INVISIBLE (-1600 3625);
FORCEPROP 1 LAST HDL_TAP TRUE
J 0
(-1275 3550);
DISPLAY 1.234043 (-1275 3550);
PAINT GREEN (-1275 3550);
DISPLAY INVISIBLE (-1275 3550);
FORCEPROP 1 LAST PATH I46
J 0
(-1602 3675);
DISPLAY 0.872340 (-1602 3675);
PAINT GREEN (-1602 3675);
DISPLAY INVISIBLE (-1602 3675);
FORCEADD TAP..6
(-1600 3625);
FORCEPROP 3 LASTPIN (-1550 3625) SIG_NAME M_K_MA<0>
J 0
(-1540 3635);
DISPLAY 0.659574 (-1540 3635);
PAINT MONO (-1540 3635);
DISPLAY INVISIBLE (-1540 3635);
FORCEPROP 1 LASTPIN (-1550 3625) BN 0
J 0
(-1600 3635);
DISPLAY 0.617021 (-1600 3635);
PAINT PINK (-1600 3635);
FORCEPROP 2 LAST CDS_LIB mstr_standard
J 2
(-1600 3625);
DISPLAY 0.787234 (-1600 3625);
PAINT MONO (-1600 3625);
DISPLAY INVISIBLE (-1600 3625);
FORCEPROP 1 LAST BODY_TYPE PLUMBING
J 0
(-1600 3575);
DISPLAY 1.234043 (-1600 3575);
PAINT GREEN (-1600 3575);
DISPLAY INVISIBLE (-1600 3575);
FORCEPROP 1 LAST HDL_TAP TRUE
J 0
(-1275 3500);
DISPLAY 1.234043 (-1275 3500);
PAINT GREEN (-1275 3500);
DISPLAY INVISIBLE (-1275 3500);
FORCEPROP 1 LAST PATH I47
J 0
(-1602 3625);
DISPLAY 0.872340 (-1602 3625);
PAINT GREEN (-1602 3625);
DISPLAY INVISIBLE (-1602 3625);
FORCEADD TAP..6
(-1600 3475);
FORCEPROP 3 LASTPIN (-1550 3475) SIG_NAME M_K_BA<0>
J 0
(-1540 3485);
DISPLAY 0.659574 (-1540 3485);
PAINT MONO (-1540 3485);
DISPLAY INVISIBLE (-1540 3485);
FORCEPROP 1 LASTPIN (-1550 3475) BN 0
J 0
(-1600 3485);
DISPLAY 0.617021 (-1600 3485);
PAINT PINK (-1600 3485);
FORCEPROP 2 LAST CDS_LIB mstr_standard
J 0
(-1600 3475);
DISPLAY 0.787234 (-1600 3475);
PAINT MONO (-1600 3475);
DISPLAY INVISIBLE (-1600 3475);
FORCEPROP 1 LAST BODY_TYPE PLUMBING
J 0
(-1600 3425);
DISPLAY 1.234043 (-1600 3425);
PAINT GREEN (-1600 3425);
DISPLAY INVISIBLE (-1600 3425);
FORCEPROP 1 LAST HDL_TAP TRUE
J 0
(-1275 3350);
DISPLAY 1.234043 (-1275 3350);
PAINT GREEN (-1275 3350);
DISPLAY INVISIBLE (-1275 3350);
FORCEPROP 1 LAST PATH I48
J 0
(-1602 3475);
DISPLAY 0.872340 (-1602 3475);
PAINT GREEN (-1602 3475);
DISPLAY INVISIBLE (-1602 3475);
FORCEADD TAP..6
(-1600 3525);
FORCEPROP 3 LASTPIN (-1550 3525) SIG_NAME M_K_BA<1>
J 0
(-1540 3535);
DISPLAY 0.659574 (-1540 3535);
PAINT MONO (-1540 3535);
DISPLAY INVISIBLE (-1540 3535);
FORCEPROP 1 LASTPIN (-1550 3525) BN 1
J 0
(-1600 3535);
DISPLAY 0.617021 (-1600 3535);
PAINT PINK (-1600 3535);
FORCEPROP 2 LAST CDS_LIB mstr_standard
J 0
(-1600 3525);
DISPLAY 0.787234 (-1600 3525);
PAINT MONO (-1600 3525);
DISPLAY INVISIBLE (-1600 3525);
FORCEPROP 1 LAST BODY_TYPE PLUMBING
J 0
(-1600 3475);
DISPLAY 1.234043 (-1600 3475);
PAINT GREEN (-1600 3475);
DISPLAY INVISIBLE (-1600 3475);
FORCEPROP 1 LAST HDL_TAP TRUE
J 0
(-1275 3400);
DISPLAY 1.234043 (-1275 3400);
PAINT GREEN (-1275 3400);
DISPLAY INVISIBLE (-1275 3400);
FORCEPROP 1 LAST PATH I49
J 0
(-1602 3525);
DISPLAY 0.872340 (-1602 3525);
PAINT GREEN (-1602 3525);
DISPLAY INVISIBLE (-1602 3525);
FORCEADD PVPP_KLM..1
(-3500 1825);
FORCEPROP 3 LASTPIN (-3500 1775) SIG_NAME PVPP_KLM\g
J 0
(-3490 1785);
DISPLAY 0.659574 (-3490 1785);
PAINT MONO (-3490 1785);
DISPLAY INVISIBLE (-3490 1785);
FORCEPROP 1 LAST VOLTAGE 2.5V
J 0
(-3545 1782);
DISPLAY 0.340426 (-3545 1782);
PAINT SKYBLUE (-3545 1782);
DISPLAY INVISIBLE (-3545 1782);
FORCEPROP 0 LAST BOM_COST MEM
J 0
(-3500 1925);
PAINT ORANGE (-3500 1925);
DISPLAY INVISIBLE (-3500 1925);
FORCEPROP 2 LAST CDS_LIB mstr_symbols
J 0
(-3500 1825);
PAINT ORANGE (-3500 1825);
DISPLAY INVISIBLE (-3500 1825);
FORCEPROP 1 LAST BODY_TYPE PLUMBING
J 0
(-3545 1782);
DISPLAY 0.340426 (-3545 1782);
PAINT GREEN (-3545 1782);
DISPLAY INVISIBLE (-3545 1782);
FORCEPROP 1 LAST PATH I5
J 0
(-3450 1850);
DISPLAY 0.872340 (-3450 1850);
PAINT AQUA (-3450 1850);
DISPLAY INVISIBLE (-3450 1850);
FORCEPROP 2 LAST ROOM DDR4_CH_C
J 0
(-3500 1925);
PAINT ORANGE (-3500 1925);
DISPLAY INVISIBLE (-3500 1925);
FORCEPROP 1 LAST HDL_POWER PVPP_KLM
J 1
(-3500 1875);
DISPLAY 0.872340 (-3500 1875);
PAINT GREEN (-3500 1875);
DISPLAY INVISIBLE (-3500 1875);
FORCEADD TAP..6
R 2
(-100 1325);
FORCEPROP 3 LASTPIN (-150 1325) SIG_NAME M_K_DQ<0>
J 0
(-140 1335);
DISPLAY 0.659574 (-140 1335);
PAINT MONO (-140 1335);
DISPLAY INVISIBLE (-140 1335);
FORCEPROP 1 LASTPIN (-150 1325) BN 0
J 2
(-100 1335);
DISPLAY 0.617021 (-100 1335);
PAINT PINK (-100 1335);
FORCEPROP 2 LAST CDS_LIB mstr_standard
J 2
(-100 1325);
DISPLAY 0.787234 (-100 1325);
PAINT MONO (-100 1325);
DISPLAY INVISIBLE (-100 1325);
FORCEPROP 1 LAST BODY_TYPE PLUMBING
J 2
(-100 1275);
DISPLAY 1.234043 (-100 1275);
PAINT GREEN (-100 1275);
DISPLAY INVISIBLE (-100 1275);
FORCEPROP 1 LAST HDL_TAP TRUE
J 2
(-425 1200);
DISPLAY 1.234043 (-425 1200);
PAINT GREEN (-425 1200);
DISPLAY INVISIBLE (-425 1200);
FORCEPROP 1 LAST PATH I50
J 2
(-98 1325);
DISPLAY 0.872340 (-98 1325);
PAINT GREEN (-98 1325);
DISPLAY INVISIBLE (-98 1325);
FORCEADD TAP..6
R 2
(-100 1375);
FORCEPROP 3 LASTPIN (-150 1375) SIG_NAME M_K_DQ<1>
J 0
(-140 1385);
DISPLAY 0.659574 (-140 1385);
PAINT MONO (-140 1385);
DISPLAY INVISIBLE (-140 1385);
FORCEPROP 1 LASTPIN (-150 1375) BN 1
J 2
(-100 1385);
DISPLAY 0.617021 (-100 1385);
PAINT PINK (-100 1385);
FORCEPROP 2 LAST CDS_LIB mstr_standard
J 2
(-100 1375);
DISPLAY 0.787234 (-100 1375);
PAINT MONO (-100 1375);
DISPLAY INVISIBLE (-100 1375);
FORCEPROP 1 LAST BODY_TYPE PLUMBING
J 2
(-100 1325);
DISPLAY 1.234043 (-100 1325);
PAINT GREEN (-100 1325);
DISPLAY INVISIBLE (-100 1325);
FORCEPROP 1 LAST HDL_TAP TRUE
J 2
(-425 1250);
DISPLAY 1.234043 (-425 1250);
PAINT GREEN (-425 1250);
DISPLAY INVISIBLE (-425 1250);
FORCEPROP 1 LAST PATH I51
J 2
(-98 1375);
DISPLAY 0.872340 (-98 1375);
PAINT GREEN (-98 1375);
DISPLAY INVISIBLE (-98 1375);
FORCEADD TAP..6
R 2
(-100 1425);
FORCEPROP 3 LASTPIN (-150 1425) SIG_NAME M_K_DQ<2>
J 0
(-140 1435);
DISPLAY 0.659574 (-140 1435);
PAINT MONO (-140 1435);
DISPLAY INVISIBLE (-140 1435);
FORCEPROP 1 LASTPIN (-150 1425) BN 2
J 2
(-100 1435);
DISPLAY 0.617021 (-100 1435);
PAINT PINK (-100 1435);
FORCEPROP 2 LAST CDS_LIB mstr_standard
J 2
(-100 1425);
DISPLAY 0.787234 (-100 1425);
PAINT MONO (-100 1425);
DISPLAY INVISIBLE (-100 1425);
FORCEPROP 1 LAST BODY_TYPE PLUMBING
J 2
(-100 1375);
DISPLAY 1.234043 (-100 1375);
PAINT GREEN (-100 1375);
DISPLAY INVISIBLE (-100 1375);
FORCEPROP 1 LAST HDL_TAP TRUE
J 2
(-425 1300);
DISPLAY 1.234043 (-425 1300);
PAINT GREEN (-425 1300);
DISPLAY INVISIBLE (-425 1300);
FORCEPROP 1 LAST PATH I52
J 2
(-98 1425);
DISPLAY 0.872340 (-98 1425);
PAINT GREEN (-98 1425);
DISPLAY INVISIBLE (-98 1425);
FORCEADD TAP..6
R 2
(-100 1475);
FORCEPROP 3 LASTPIN (-150 1475) SIG_NAME M_K_DQ<3>
J 0
(-140 1485);
DISPLAY 0.659574 (-140 1485);
PAINT MONO (-140 1485);
DISPLAY INVISIBLE (-140 1485);
FORCEPROP 1 LASTPIN (-150 1475) BN 3
J 2
(-100 1485);
DISPLAY 0.617021 (-100 1485);
PAINT PINK (-100 1485);
FORCEPROP 2 LAST CDS_LIB mstr_standard
J 2
(-100 1475);
DISPLAY 0.787234 (-100 1475);
PAINT MONO (-100 1475);
DISPLAY INVISIBLE (-100 1475);
FORCEPROP 1 LAST BODY_TYPE PLUMBING
J 2
(-100 1425);
DISPLAY 1.234043 (-100 1425);
PAINT GREEN (-100 1425);
DISPLAY INVISIBLE (-100 1425);
FORCEPROP 1 LAST HDL_TAP TRUE
J 2
(-425 1350);
DISPLAY 1.234043 (-425 1350);
PAINT GREEN (-425 1350);
DISPLAY INVISIBLE (-425 1350);
FORCEPROP 1 LAST PATH I53
J 2
(-98 1475);
DISPLAY 0.872340 (-98 1475);
PAINT GREEN (-98 1475);
DISPLAY INVISIBLE (-98 1475);
FORCEADD TAP..6
R 2
(-100 1525);
FORCEPROP 3 LASTPIN (-150 1525) SIG_NAME M_K_DQ<4>
J 0
(-140 1535);
DISPLAY 0.659574 (-140 1535);
PAINT MONO (-140 1535);
DISPLAY INVISIBLE (-140 1535);
FORCEPROP 1 LASTPIN (-150 1525) BN 4
J 2
(-100 1535);
DISPLAY 0.617021 (-100 1535);
PAINT PINK (-100 1535);
FORCEPROP 2 LAST CDS_LIB mstr_standard
J 2
(-100 1525);
DISPLAY 0.787234 (-100 1525);
PAINT MONO (-100 1525);
DISPLAY INVISIBLE (-100 1525);
FORCEPROP 1 LAST BODY_TYPE PLUMBING
J 2
(-100 1475);
DISPLAY 1.234043 (-100 1475);
PAINT GREEN (-100 1475);
DISPLAY INVISIBLE (-100 1475);
FORCEPROP 1 LAST HDL_TAP TRUE
J 2
(-425 1400);
DISPLAY 1.234043 (-425 1400);
PAINT GREEN (-425 1400);
DISPLAY INVISIBLE (-425 1400);
FORCEPROP 1 LAST PATH I54
J 2
(-98 1525);
DISPLAY 0.872340 (-98 1525);
PAINT GREEN (-98 1525);
DISPLAY INVISIBLE (-98 1525);
FORCEADD TAP..6
R 2
(-100 1625);
FORCEPROP 3 LASTPIN (-150 1625) SIG_NAME M_K_DQ<6>
J 0
(-140 1635);
DISPLAY 0.659574 (-140 1635);
PAINT MONO (-140 1635);
DISPLAY INVISIBLE (-140 1635);
FORCEPROP 1 LASTPIN (-150 1625) BN 6
J 2
(-100 1635);
DISPLAY 0.617021 (-100 1635);
PAINT PINK (-100 1635);
FORCEPROP 2 LAST CDS_LIB mstr_standard
J 2
(-100 1625);
DISPLAY 0.787234 (-100 1625);
PAINT MONO (-100 1625);
DISPLAY INVISIBLE (-100 1625);
FORCEPROP 1 LAST BODY_TYPE PLUMBING
J 2
(-100 1575);
DISPLAY 1.234043 (-100 1575);
PAINT GREEN (-100 1575);
DISPLAY INVISIBLE (-100 1575);
FORCEPROP 1 LAST HDL_TAP TRUE
J 2
(-425 1500);
DISPLAY 1.234043 (-425 1500);
PAINT GREEN (-425 1500);
DISPLAY INVISIBLE (-425 1500);
FORCEPROP 1 LAST PATH I55
J 2
(-98 1625);
DISPLAY 0.872340 (-98 1625);
PAINT GREEN (-98 1625);
DISPLAY INVISIBLE (-98 1625);
FORCEADD TAP..6
R 2
(-100 1575);
FORCEPROP 3 LASTPIN (-150 1575) SIG_NAME M_K_DQ<5>
J 0
(-140 1585);
DISPLAY 0.659574 (-140 1585);
PAINT MONO (-140 1585);
DISPLAY INVISIBLE (-140 1585);
FORCEPROP 1 LASTPIN (-150 1575) BN 5
J 2
(-100 1585);
DISPLAY 0.617021 (-100 1585);
PAINT PINK (-100 1585);
FORCEPROP 2 LAST CDS_LIB mstr_standard
J 2
(-100 1575);
DISPLAY 0.787234 (-100 1575);
PAINT MONO (-100 1575);
DISPLAY INVISIBLE (-100 1575);
FORCEPROP 1 LAST BODY_TYPE PLUMBING
J 2
(-100 1525);
DISPLAY 1.234043 (-100 1525);
PAINT GREEN (-100 1525);
DISPLAY INVISIBLE (-100 1525);
FORCEPROP 1 LAST HDL_TAP TRUE
J 2
(-425 1450);
DISPLAY 1.234043 (-425 1450);
PAINT GREEN (-425 1450);
DISPLAY INVISIBLE (-425 1450);
FORCEPROP 1 LAST PATH I56
J 2
(-98 1575);
DISPLAY 0.872340 (-98 1575);
PAINT GREEN (-98 1575);
DISPLAY INVISIBLE (-98 1575);
FORCEADD SCONN288_H44441003..4
(1450 1725);
FORCEPROP 1 LAST PART_NUMBER H44441-003
J 0
(1000 675);
DISPLAY 0.617021 (1000 675);
PAINT BLUE (1000 675);
FORCEPROP 1 LAST MATERIAL SCONN
J 0
(1000 2775);
DISPLAY 0.617021 (1000 2775);
PAINT SKYBLUE (1000 2775);
FORCEPROP 2 LASTPIN (950 2275) $PN 77
J 2
(940 2285);
DISPLAY 0.617021 (940 2285);
PAINT ORANGE (940 2285);
FORCEPROP 2 LASTPIN (950 2225) $PN 221
J 2
(940 2235);
DISPLAY 0.617021 (940 2235);
PAINT ORANGE (940 2235);
FORCEPROP 2 LASTPIN (950 2575) $PN 142
J 2
(940 2585);
DISPLAY 0.617021 (940 2585);
PAINT ORANGE (940 2585);
FORCEPROP 2 LASTPIN (950 2525) $PN 143
J 2
(940 2535);
DISPLAY 0.617021 (940 2535);
PAINT ORANGE (940 2535);
FORCEPROP 2 LASTPIN (950 2475) $PN 288
J 2
(940 2485);
DISPLAY 0.617021 (940 2485);
PAINT ORANGE (940 2485);
FORCEPROP 2 LASTPIN (950 2425) $PN 286
J 2
(940 2435);
DISPLAY 0.617021 (940 2435);
PAINT ORANGE (940 2435);
FORCEPROP 2 LASTPIN (950 2375) $PN 287
J 2
(940 2385);
DISPLAY 0.617021 (940 2385);
PAINT ORANGE (940 2385);
FORCEPROP 2 LASTPIN (950 2125) $PN 59
J 2
(940 2135);
DISPLAY 0.617021 (940 2135);
PAINT ORANGE (940 2135);
FORCEPROP 2 LASTPIN (950 2075) $PN 61
J 2
(940 2085);
DISPLAY 0.617021 (940 2085);
PAINT ORANGE (940 2085);
FORCEPROP 2 LASTPIN (950 2025) $PN 64
J 2
(940 2035);
DISPLAY 0.617021 (940 2035);
PAINT ORANGE (940 2035);
FORCEPROP 2 LASTPIN (950 1975) $PN 67
J 2
(940 1985);
DISPLAY 0.617021 (940 1985);
PAINT ORANGE (940 1985);
FORCEPROP 2 LASTPIN (950 1925) $PN 70
J 2
(940 1935);
DISPLAY 0.617021 (940 1935);
PAINT ORANGE (940 1935);
FORCEPROP 2 LASTPIN (950 1875) $PN 73
J 2
(940 1885);
DISPLAY 0.617021 (940 1885);
PAINT ORANGE (940 1885);
FORCEPROP 2 LASTPIN (950 1825) $PN 76
J 2
(940 1835);
DISPLAY 0.617021 (940 1835);
PAINT ORANGE (940 1835);
FORCEPROP 2 LASTPIN (950 1775) $PN 80
J 2
(940 1785);
DISPLAY 0.617021 (940 1785);
PAINT ORANGE (940 1785);
FORCEPROP 2 LASTPIN (950 1725) $PN 83
J 2
(940 1735);
DISPLAY 0.617021 (940 1735);
PAINT ORANGE (940 1735);
FORCEPROP 2 LASTPIN (950 1675) $PN 85
J 2
(940 1685);
DISPLAY 0.617021 (940 1685);
PAINT ORANGE (940 1685);
FORCEPROP 2 LASTPIN (950 1625) $PN 88
J 2
(940 1635);
DISPLAY 0.617021 (940 1635);
PAINT ORANGE (940 1635);
FORCEPROP 2 LASTPIN (950 1575) $PN 90
J 2
(940 1585);
DISPLAY 0.617021 (940 1585);
PAINT ORANGE (940 1585);
FORCEPROP 2 LASTPIN (950 1525) $PN 92
J 2
(940 1535);
DISPLAY 0.617021 (940 1535);
PAINT ORANGE (940 1535);
FORCEPROP 2 LASTPIN (950 1475) $PN 204
J 2
(940 1485);
DISPLAY 0.617021 (940 1485);
PAINT ORANGE (940 1485);
FORCEPROP 2 LASTPIN (950 1425) $PN 206
J 2
(940 1435);
DISPLAY 0.617021 (940 1435);
PAINT ORANGE (940 1435);
FORCEPROP 2 LASTPIN (950 1375) $PN 209
J 2
(940 1385);
DISPLAY 0.617021 (940 1385);
PAINT ORANGE (940 1385);
FORCEPROP 2 LASTPIN (950 1325) $PN 212
J 2
(940 1335);
DISPLAY 0.617021 (940 1335);
PAINT ORANGE (940 1335);
FORCEPROP 2 LASTPIN (950 1275) $PN 215
J 2
(940 1285);
DISPLAY 0.617021 (940 1285);
PAINT ORANGE (940 1285);
FORCEPROP 2 LASTPIN (950 1225) $PN 217
J 2
(940 1235);
DISPLAY 0.617021 (940 1235);
PAINT ORANGE (940 1235);
FORCEPROP 2 LASTPIN (950 1175) $PN 220
J 2
(940 1185);
DISPLAY 0.617021 (940 1185);
PAINT ORANGE (940 1185);
FORCEPROP 2 LASTPIN (950 1125) $PN 223
J 2
(940 1135);
DISPLAY 0.617021 (940 1135);
PAINT ORANGE (940 1135);
FORCEPROP 2 LASTPIN (950 1075) $PN 226
J 2
(940 1085);
DISPLAY 0.617021 (940 1085);
PAINT ORANGE (940 1085);
FORCEPROP 2 LASTPIN (950 1025) $PN 229
J 2
(940 1035);
DISPLAY 0.617021 (940 1035);
PAINT ORANGE (940 1035);
FORCEPROP 2 LASTPIN (950 975) $PN 231
J 2
(940 985);
DISPLAY 0.617021 (940 985);
PAINT ORANGE (940 985);
FORCEPROP 2 LASTPIN (950 925) $PN 233
J 2
(940 935);
DISPLAY 0.617021 (940 935);
PAINT ORANGE (940 935);
FORCEPROP 2 LASTPIN (950 875) $PN 236
J 2
(940 885);
DISPLAY 0.617021 (940 885);
PAINT ORANGE (940 885);
FORCEPROP 2 LASTPIN (1950 2575) $PN 1
J 0
(1960 2585);
DISPLAY 0.617021 (1960 2585);
PAINT ORANGE (1960 2585);
FORCEPROP 1 LAST LOCATION J9M1
J 0
(1000 2825);
DISPLAY 0.617021 (1000 2825);
PAINT AQUA (1000 2825);
FORCEPROP 2 LASTPIN (1950 2525) $PN 145
J 0
(1960 2535);
DISPLAY 0.617021 (1960 2535);
PAINT ORANGE (1960 2535);
FORCEPROP 0 LAST BOM_SS NOPOP
J 0
(1266 2751);
DISPLAY 1.021277 (1266 2751);
PAINT BROWN (1266 2751);
DISPLAY BOTH (1266 2751);
FORCEPROP 1 LAST PACK_TYPE PIP
J 0
(1000 2875);
PAINT SKYBLUE (1000 2875);
DISPLAY INVISIBLE (1000 2875);
FORCEPROP 2 LAST BOM_COST MEM
J 0
(1450 1725);
PAINT ORANGE (1450 1725);
DISPLAY INVISIBLE (1450 1725);
FORCEPROP 2 LAST CDS_LIB mstr_sconn
J 0
(1450 1725);
PAINT ORANGE (1450 1725);
DISPLAY INVISIBLE (1450 1725);
FORCEPROP 2 LAST SEC_TYPE PIP
J 0
(1000 2875);
DISPLAY 1.021277 (1000 2875);
PAINT ORANGE (1000 2875);
DISPLAY INVISIBLE (1000 2875);
FORCEPROP 2 LAST SEC 4
J 0
(1000 2875);
DISPLAY 0.680851 (1000 2875);
PAINT MONO (1000 2875);
DISPLAY INVISIBLE (1000 2875);
FORCEPROP 2 LAST CDS_LOCATION J9M1
J 0
(1000 2825);
DISPLAY 0.617021 (1000 2825);
PAINT AQUA (1000 2825);
DISPLAY INVISIBLE (1000 2825);
FORCEPROP 1 LAST PATH I57
J 0
(1450 2775);
PAINT GREEN (1450 2775);
DISPLAY INVISIBLE (1450 2775);
FORCEPROP 2 LAST ROOM DDR4_CH_K
J 0
(1450 1725);
PAINT ORANGE (1450 1725);
DISPLAY INVISIBLE (1450 1725);
FORCEADD TAP..6
R 2
(-100 1775);
FORCEPROP 3 LASTPIN (-150 1775) SIG_NAME M_K_DQ<9>
J 0
(-140 1785);
DISPLAY 0.659574 (-140 1785);
PAINT MONO (-140 1785);
DISPLAY INVISIBLE (-140 1785);
FORCEPROP 1 LASTPIN (-150 1775) BN 9
J 2
(-100 1785);
DISPLAY 0.617021 (-100 1785);
PAINT PINK (-100 1785);
FORCEPROP 2 LAST CDS_LIB mstr_standard
J 2
(-100 1775);
DISPLAY 0.787234 (-100 1775);
PAINT MONO (-100 1775);
DISPLAY INVISIBLE (-100 1775);
FORCEPROP 1 LAST BODY_TYPE PLUMBING
J 2
(-100 1725);
DISPLAY 1.234043 (-100 1725);
PAINT GREEN (-100 1725);
DISPLAY INVISIBLE (-100 1725);
FORCEPROP 1 LAST HDL_TAP TRUE
J 2
(-425 1650);
DISPLAY 1.234043 (-425 1650);
PAINT GREEN (-425 1650);
DISPLAY INVISIBLE (-425 1650);
FORCEPROP 1 LAST PATH I58
J 2
(-98 1775);
DISPLAY 0.872340 (-98 1775);
PAINT GREEN (-98 1775);
DISPLAY INVISIBLE (-98 1775);
FORCEADD TAP..6
R 2
(-100 1675);
FORCEPROP 3 LASTPIN (-150 1675) SIG_NAME M_K_DQ<7>
J 0
(-140 1685);
DISPLAY 0.659574 (-140 1685);
PAINT MONO (-140 1685);
DISPLAY INVISIBLE (-140 1685);
FORCEPROP 1 LASTPIN (-150 1675) BN 7
J 2
(-100 1685);
DISPLAY 0.617021 (-100 1685);
PAINT PINK (-100 1685);
FORCEPROP 2 LAST CDS_LIB mstr_standard
J 2
(-100 1675);
DISPLAY 0.787234 (-100 1675);
PAINT MONO (-100 1675);
DISPLAY INVISIBLE (-100 1675);
FORCEPROP 1 LAST BODY_TYPE PLUMBING
J 2
(-100 1625);
DISPLAY 1.234043 (-100 1625);
PAINT GREEN (-100 1625);
DISPLAY INVISIBLE (-100 1625);
FORCEPROP 1 LAST HDL_TAP TRUE
J 2
(-425 1550);
DISPLAY 1.234043 (-425 1550);
PAINT GREEN (-425 1550);
DISPLAY INVISIBLE (-425 1550);
FORCEPROP 1 LAST PATH I59
J 2
(-98 1675);
DISPLAY 0.872340 (-98 1675);
PAINT GREEN (-98 1675);
DISPLAY INVISIBLE (-98 1675);
FORCEADD OFFPAGE..5
(-2425 1825);
FORCEPROP 2 LAST $XR1 60 
J 0
(-2739 1825);
DISPLAY 0.638298 (-2739 1825);
PAINT MONO (-2739 1825);
FORCEPROP 2 LAST $XR0 83 
J 0
(-2649 1825);
DISPLAY 0.638298 (-2649 1825);
PAINT MONO (-2649 1825);
FORCEPROP 2 LAST CDS_LIB mstr_standard
J 0
(-2425 1825);
DISPLAY 0.787234 (-2425 1825);
PAINT MONO (-2425 1825);
DISPLAY INVISIBLE (-2425 1825);
FORCEPROP 1 LAST OFFPAGE TRUE
J 0
(-2100 1700);
DISPLAY 1.404255 (-2100 1700);
PAINT GREEN (-2100 1700);
DISPLAY INVISIBLE (-2100 1700);
FORCEPROP 1 LAST COMMENT_BODY TRUE
J 0
(-2325 1750);
DISPLAY 1.404255 (-2325 1750);
PAINT GREEN (-2325 1750);
DISPLAY INVISIBLE (-2325 1750);
FORCEPROP 2 LAST PATH I6
J 0
(-2625 1875);
DISPLAY 1.021277 (-2625 1875);
PAINT ORANGE (-2625 1875);
DISPLAY INVISIBLE (-2625 1875);
FORCEADD TAP..6
R 2
(-100 1725);
FORCEPROP 3 LASTPIN (-150 1725) SIG_NAME M_K_DQ<8>
J 0
(-140 1735);
DISPLAY 0.659574 (-140 1735);
PAINT MONO (-140 1735);
DISPLAY INVISIBLE (-140 1735);
FORCEPROP 1 LASTPIN (-150 1725) BN 8
J 2
(-100 1735);
DISPLAY 0.617021 (-100 1735);
PAINT PINK (-100 1735);
FORCEPROP 2 LAST CDS_LIB mstr_standard
J 2
(-100 1725);
DISPLAY 0.787234 (-100 1725);
PAINT MONO (-100 1725);
DISPLAY INVISIBLE (-100 1725);
FORCEPROP 1 LAST BODY_TYPE PLUMBING
J 2
(-100 1675);
DISPLAY 1.234043 (-100 1675);
PAINT GREEN (-100 1675);
DISPLAY INVISIBLE (-100 1675);
FORCEPROP 1 LAST HDL_TAP TRUE
J 2
(-425 1600);
DISPLAY 1.234043 (-425 1600);
PAINT GREEN (-425 1600);
DISPLAY INVISIBLE (-425 1600);
FORCEPROP 1 LAST PATH I60
J 2
(-98 1725);
DISPLAY 0.872340 (-98 1725);
PAINT GREEN (-98 1725);
DISPLAY INVISIBLE (-98 1725);
FORCEADD TAP..6
R 2
(-100 1875);
FORCEPROP 3 LASTPIN (-150 1875) SIG_NAME M_K_DQ<11>
J 0
(-140 1885);
DISPLAY 0.659574 (-140 1885);
PAINT MONO (-140 1885);
DISPLAY INVISIBLE (-140 1885);
FORCEPROP 1 LASTPIN (-150 1875) BN 11
J 2
(-100 1885);
DISPLAY 0.617021 (-100 1885);
PAINT PINK (-100 1885);
FORCEPROP 2 LAST CDS_LIB mstr_standard
J 2
(-100 1875);
DISPLAY 0.787234 (-100 1875);
PAINT MONO (-100 1875);
DISPLAY INVISIBLE (-100 1875);
FORCEPROP 1 LAST BODY_TYPE PLUMBING
J 2
(-100 1825);
DISPLAY 1.234043 (-100 1825);
PAINT GREEN (-100 1825);
DISPLAY INVISIBLE (-100 1825);
FORCEPROP 1 LAST HDL_TAP TRUE
J 2
(-425 1750);
DISPLAY 1.234043 (-425 1750);
PAINT GREEN (-425 1750);
DISPLAY INVISIBLE (-425 1750);
FORCEPROP 1 LAST PATH I61
J 2
(-98 1875);
DISPLAY 0.872340 (-98 1875);
PAINT GREEN (-98 1875);
DISPLAY INVISIBLE (-98 1875);
FORCEADD TAP..6
R 2
(-100 1925);
FORCEPROP 3 LASTPIN (-150 1925) SIG_NAME M_K_DQ<12>
J 0
(-140 1935);
DISPLAY 0.659574 (-140 1935);
PAINT MONO (-140 1935);
DISPLAY INVISIBLE (-140 1935);
FORCEPROP 1 LASTPIN (-150 1925) BN 12
J 2
(-100 1935);
DISPLAY 0.617021 (-100 1935);
PAINT PINK (-100 1935);
FORCEPROP 2 LAST CDS_LIB mstr_standard
J 2
(-100 1925);
DISPLAY 0.787234 (-100 1925);
PAINT MONO (-100 1925);
DISPLAY INVISIBLE (-100 1925);
FORCEPROP 1 LAST BODY_TYPE PLUMBING
J 2
(-100 1875);
DISPLAY 1.234043 (-100 1875);
PAINT GREEN (-100 1875);
DISPLAY INVISIBLE (-100 1875);
FORCEPROP 1 LAST HDL_TAP TRUE
J 2
(-425 1800);
DISPLAY 1.234043 (-425 1800);
PAINT GREEN (-425 1800);
DISPLAY INVISIBLE (-425 1800);
FORCEPROP 1 LAST PATH I62
J 2
(-98 1925);
DISPLAY 0.872340 (-98 1925);
PAINT GREEN (-98 1925);
DISPLAY INVISIBLE (-98 1925);
FORCEADD TAP..6
R 2
(-100 1825);
FORCEPROP 3 LASTPIN (-150 1825) SIG_NAME M_K_DQ<10>
J 0
(-140 1835);
DISPLAY 0.659574 (-140 1835);
PAINT MONO (-140 1835);
DISPLAY INVISIBLE (-140 1835);
FORCEPROP 1 LASTPIN (-150 1825) BN 10
J 2
(-100 1835);
DISPLAY 0.617021 (-100 1835);
PAINT PINK (-100 1835);
FORCEPROP 2 LAST CDS_LIB mstr_standard
J 2
(-100 1825);
DISPLAY 0.787234 (-100 1825);
PAINT MONO (-100 1825);
DISPLAY INVISIBLE (-100 1825);
FORCEPROP 1 LAST BODY_TYPE PLUMBING
J 2
(-100 1775);
DISPLAY 1.234043 (-100 1775);
PAINT GREEN (-100 1775);
DISPLAY INVISIBLE (-100 1775);
FORCEPROP 1 LAST HDL_TAP TRUE
J 2
(-425 1700);
DISPLAY 1.234043 (-425 1700);
PAINT GREEN (-425 1700);
DISPLAY INVISIBLE (-425 1700);
FORCEPROP 1 LAST PATH I63
J 2
(-98 1825);
DISPLAY 0.872340 (-98 1825);
PAINT GREEN (-98 1825);
DISPLAY INVISIBLE (-98 1825);
FORCEADD TAP..6
R 2
(-100 2025);
FORCEPROP 3 LASTPIN (-150 2025) SIG_NAME M_K_DQ<14>
J 0
(-140 2035);
DISPLAY 0.659574 (-140 2035);
PAINT MONO (-140 2035);
DISPLAY INVISIBLE (-140 2035);
FORCEPROP 1 LASTPIN (-150 2025) BN 14
J 2
(-100 2035);
DISPLAY 0.617021 (-100 2035);
PAINT PINK (-100 2035);
FORCEPROP 2 LAST CDS_LIB mstr_standard
J 2
(-100 2025);
DISPLAY 0.787234 (-100 2025);
PAINT MONO (-100 2025);
DISPLAY INVISIBLE (-100 2025);
FORCEPROP 1 LAST BODY_TYPE PLUMBING
J 2
(-100 1975);
DISPLAY 1.234043 (-100 1975);
PAINT GREEN (-100 1975);
DISPLAY INVISIBLE (-100 1975);
FORCEPROP 1 LAST HDL_TAP TRUE
J 2
(-425 1900);
DISPLAY 1.234043 (-425 1900);
PAINT GREEN (-425 1900);
DISPLAY INVISIBLE (-425 1900);
FORCEPROP 1 LAST PATH I64
J 2
(-98 2025);
DISPLAY 0.872340 (-98 2025);
PAINT GREEN (-98 2025);
DISPLAY INVISIBLE (-98 2025);
FORCEADD TAP..6
R 2
(-100 1975);
FORCEPROP 3 LASTPIN (-150 1975) SIG_NAME M_K_DQ<13>
J 0
(-140 1985);
DISPLAY 0.659574 (-140 1985);
PAINT MONO (-140 1985);
DISPLAY INVISIBLE (-140 1985);
FORCEPROP 1 LASTPIN (-150 1975) BN 13
J 2
(-100 1985);
DISPLAY 0.617021 (-100 1985);
PAINT PINK (-100 1985);
FORCEPROP 2 LAST CDS_LIB mstr_standard
J 2
(-100 1975);
DISPLAY 0.787234 (-100 1975);
PAINT MONO (-100 1975);
DISPLAY INVISIBLE (-100 1975);
FORCEPROP 1 LAST BODY_TYPE PLUMBING
J 2
(-100 1925);
DISPLAY 1.234043 (-100 1925);
PAINT GREEN (-100 1925);
DISPLAY INVISIBLE (-100 1925);
FORCEPROP 1 LAST HDL_TAP TRUE
J 2
(-425 1850);
DISPLAY 1.234043 (-425 1850);
PAINT GREEN (-425 1850);
DISPLAY INVISIBLE (-425 1850);
FORCEPROP 1 LAST PATH I65
J 2
(-98 1975);
DISPLAY 0.872340 (-98 1975);
PAINT GREEN (-98 1975);
DISPLAY INVISIBLE (-98 1975);
FORCEADD TAP..6
R 2
(-100 2125);
FORCEPROP 3 LASTPIN (-150 2125) SIG_NAME M_K_DQ<16>
J 0
(-140 2135);
DISPLAY 0.659574 (-140 2135);
PAINT MONO (-140 2135);
DISPLAY INVISIBLE (-140 2135);
FORCEPROP 1 LASTPIN (-150 2125) BN 16
J 2
(-100 2135);
DISPLAY 0.617021 (-100 2135);
PAINT PINK (-100 2135);
FORCEPROP 2 LAST CDS_LIB mstr_standard
J 2
(-100 2125);
DISPLAY 0.787234 (-100 2125);
PAINT MONO (-100 2125);
DISPLAY INVISIBLE (-100 2125);
FORCEPROP 1 LAST BODY_TYPE PLUMBING
J 2
(-100 2075);
DISPLAY 1.234043 (-100 2075);
PAINT GREEN (-100 2075);
DISPLAY INVISIBLE (-100 2075);
FORCEPROP 1 LAST HDL_TAP TRUE
J 2
(-425 2000);
DISPLAY 1.234043 (-425 2000);
PAINT GREEN (-425 2000);
DISPLAY INVISIBLE (-425 2000);
FORCEPROP 1 LAST PATH I66
J 2
(-98 2125);
DISPLAY 0.872340 (-98 2125);
PAINT GREEN (-98 2125);
DISPLAY INVISIBLE (-98 2125);
FORCEADD TAP..6
R 2
(-100 2175);
FORCEPROP 3 LASTPIN (-150 2175) SIG_NAME M_K_DQ<17>
J 0
(-140 2185);
DISPLAY 0.659574 (-140 2185);
PAINT MONO (-140 2185);
DISPLAY INVISIBLE (-140 2185);
FORCEPROP 1 LASTPIN (-150 2175) BN 17
J 2
(-100 2185);
DISPLAY 0.617021 (-100 2185);
PAINT PINK (-100 2185);
FORCEPROP 2 LAST CDS_LIB mstr_standard
J 2
(-100 2175);
DISPLAY 0.787234 (-100 2175);
PAINT MONO (-100 2175);
DISPLAY INVISIBLE (-100 2175);
FORCEPROP 1 LAST BODY_TYPE PLUMBING
J 2
(-100 2125);
DISPLAY 1.234043 (-100 2125);
PAINT GREEN (-100 2125);
DISPLAY INVISIBLE (-100 2125);
FORCEPROP 1 LAST HDL_TAP TRUE
J 2
(-425 2050);
DISPLAY 1.234043 (-425 2050);
PAINT GREEN (-425 2050);
DISPLAY INVISIBLE (-425 2050);
FORCEPROP 1 LAST PATH I67
J 2
(-98 2175);
DISPLAY 0.872340 (-98 2175);
PAINT GREEN (-98 2175);
DISPLAY INVISIBLE (-98 2175);
FORCEADD TAP..6
R 2
(-100 2075);
FORCEPROP 3 LASTPIN (-150 2075) SIG_NAME M_K_DQ<15>
J 0
(-140 2085);
DISPLAY 0.659574 (-140 2085);
PAINT MONO (-140 2085);
DISPLAY INVISIBLE (-140 2085);
FORCEPROP 1 LASTPIN (-150 2075) BN 15
J 2
(-100 2085);
DISPLAY 0.617021 (-100 2085);
PAINT PINK (-100 2085);
FORCEPROP 2 LAST CDS_LIB mstr_standard
J 2
(-100 2075);
DISPLAY 0.787234 (-100 2075);
PAINT MONO (-100 2075);
DISPLAY INVISIBLE (-100 2075);
FORCEPROP 1 LAST BODY_TYPE PLUMBING
J 2
(-100 2025);
DISPLAY 1.234043 (-100 2025);
PAINT GREEN (-100 2025);
DISPLAY INVISIBLE (-100 2025);
FORCEPROP 1 LAST HDL_TAP TRUE
J 2
(-425 1950);
DISPLAY 1.234043 (-425 1950);
PAINT GREEN (-425 1950);
DISPLAY INVISIBLE (-425 1950);
FORCEPROP 1 LAST PATH I68
J 2
(-98 2075);
DISPLAY 0.872340 (-98 2075);
PAINT GREEN (-98 2075);
DISPLAY INVISIBLE (-98 2075);
FORCEADD TAP..6
R 2
(-100 2275);
FORCEPROP 3 LASTPIN (-150 2275) SIG_NAME M_K_DQ<19>
J 0
(-140 2285);
DISPLAY 0.659574 (-140 2285);
PAINT MONO (-140 2285);
DISPLAY INVISIBLE (-140 2285);
FORCEPROP 1 LASTPIN (-150 2275) BN 19
J 2
(-100 2285);
DISPLAY 0.617021 (-100 2285);
PAINT PINK (-100 2285);
FORCEPROP 2 LAST CDS_LIB mstr_standard
J 2
(-100 2275);
DISPLAY 0.787234 (-100 2275);
PAINT MONO (-100 2275);
DISPLAY INVISIBLE (-100 2275);
FORCEPROP 1 LAST BODY_TYPE PLUMBING
J 2
(-100 2225);
DISPLAY 1.234043 (-100 2225);
PAINT GREEN (-100 2225);
DISPLAY INVISIBLE (-100 2225);
FORCEPROP 1 LAST HDL_TAP TRUE
J 2
(-425 2150);
DISPLAY 1.234043 (-425 2150);
PAINT GREEN (-425 2150);
DISPLAY INVISIBLE (-425 2150);
FORCEPROP 1 LAST PATH I69
J 2
(-98 2275);
DISPLAY 0.872340 (-98 2275);
PAINT GREEN (-98 2275);
DISPLAY INVISIBLE (-98 2275);
FORCEADD OFFPAGE..1
(-2400 1775);
FORCEPROP 2 LAST $XR1 83 
J 0
(-2741 1775);
DISPLAY 0.638298 (-2741 1775);
PAINT MONO (-2741 1775);
FORCEPROP 2 LAST $XR0 60 
J 0
(-2651 1775);
DISPLAY 0.638298 (-2651 1775);
PAINT MONO (-2651 1775);
FORCEPROP 2 LAST CDS_LIB mstr_standard
J 0
(-2400 1775);
DISPLAY 0.787234 (-2400 1775);
PAINT MONO (-2400 1775);
DISPLAY INVISIBLE (-2400 1775);
FORCEPROP 1 LAST OFFPAGE TRUE
J 0
(-2075 1650);
DISPLAY 0.936170 (-2075 1650);
PAINT GREEN (-2075 1650);
DISPLAY INVISIBLE (-2075 1650);
FORCEPROP 1 LAST COMMENT_BODY TRUE
J 0
(-2275 1675);
DISPLAY 0.936170 (-2275 1675);
PAINT GREEN (-2275 1675);
DISPLAY INVISIBLE (-2275 1675);
FORCEPROP 2 LAST PATH I7
J 0
(-2650 1825);
DISPLAY 1.021277 (-2650 1825);
PAINT ORANGE (-2650 1825);
DISPLAY INVISIBLE (-2650 1825);
FORCEADD TAP..6
R 2
(-100 2225);
FORCEPROP 3 LASTPIN (-150 2225) SIG_NAME M_K_DQ<18>
J 0
(-140 2235);
DISPLAY 0.659574 (-140 2235);
PAINT MONO (-140 2235);
DISPLAY INVISIBLE (-140 2235);
FORCEPROP 1 LASTPIN (-150 2225) BN 18
J 2
(-100 2235);
DISPLAY 0.617021 (-100 2235);
PAINT PINK (-100 2235);
FORCEPROP 2 LAST CDS_LIB mstr_standard
J 2
(-100 2225);
DISPLAY 0.787234 (-100 2225);
PAINT MONO (-100 2225);
DISPLAY INVISIBLE (-100 2225);
FORCEPROP 1 LAST BODY_TYPE PLUMBING
J 2
(-100 2175);
DISPLAY 1.234043 (-100 2175);
PAINT GREEN (-100 2175);
DISPLAY INVISIBLE (-100 2175);
FORCEPROP 1 LAST HDL_TAP TRUE
J 2
(-425 2100);
DISPLAY 1.234043 (-425 2100);
PAINT GREEN (-425 2100);
DISPLAY INVISIBLE (-425 2100);
FORCEPROP 1 LAST PATH I70
J 2
(-98 2225);
DISPLAY 0.872340 (-98 2225);
PAINT GREEN (-98 2225);
DISPLAY INVISIBLE (-98 2225);
FORCEADD TAP..6
R 2
(-100 2425);
FORCEPROP 3 LASTPIN (-150 2425) SIG_NAME M_K_DQ<22>
J 0
(-140 2435);
DISPLAY 0.659574 (-140 2435);
PAINT MONO (-140 2435);
DISPLAY INVISIBLE (-140 2435);
FORCEPROP 1 LASTPIN (-150 2425) BN 22
J 2
(-100 2435);
DISPLAY 0.617021 (-100 2435);
PAINT PINK (-100 2435);
FORCEPROP 2 LAST CDS_LIB mstr_standard
J 2
(-100 2425);
DISPLAY 0.787234 (-100 2425);
PAINT MONO (-100 2425);
DISPLAY INVISIBLE (-100 2425);
FORCEPROP 1 LAST BODY_TYPE PLUMBING
J 2
(-100 2375);
DISPLAY 1.234043 (-100 2375);
PAINT GREEN (-100 2375);
DISPLAY INVISIBLE (-100 2375);
FORCEPROP 1 LAST HDL_TAP TRUE
J 2
(-425 2300);
DISPLAY 1.234043 (-425 2300);
PAINT GREEN (-425 2300);
DISPLAY INVISIBLE (-425 2300);
FORCEPROP 1 LAST PATH I71
J 2
(-98 2425);
DISPLAY 0.872340 (-98 2425);
PAINT GREEN (-98 2425);
DISPLAY INVISIBLE (-98 2425);
FORCEADD TAP..6
R 2
(-100 2375);
FORCEPROP 3 LASTPIN (-150 2375) SIG_NAME M_K_DQ<21>
J 0
(-140 2385);
DISPLAY 0.659574 (-140 2385);
PAINT MONO (-140 2385);
DISPLAY INVISIBLE (-140 2385);
FORCEPROP 1 LASTPIN (-150 2375) BN 21
J 2
(-100 2385);
DISPLAY 0.617021 (-100 2385);
PAINT PINK (-100 2385);
FORCEPROP 2 LAST CDS_LIB mstr_standard
J 2
(-100 2375);
DISPLAY 0.787234 (-100 2375);
PAINT MONO (-100 2375);
DISPLAY INVISIBLE (-100 2375);
FORCEPROP 1 LAST BODY_TYPE PLUMBING
J 2
(-100 2325);
DISPLAY 1.234043 (-100 2325);
PAINT GREEN (-100 2325);
DISPLAY INVISIBLE (-100 2325);
FORCEPROP 1 LAST HDL_TAP TRUE
J 2
(-425 2250);
DISPLAY 1.234043 (-425 2250);
PAINT GREEN (-425 2250);
DISPLAY INVISIBLE (-425 2250);
FORCEPROP 1 LAST PATH I72
J 2
(-98 2375);
DISPLAY 0.872340 (-98 2375);
PAINT GREEN (-98 2375);
DISPLAY INVISIBLE (-98 2375);
FORCEADD TAP..6
R 2
(-100 2325);
FORCEPROP 3 LASTPIN (-150 2325) SIG_NAME M_K_DQ<20>
J 0
(-140 2335);
DISPLAY 0.659574 (-140 2335);
PAINT MONO (-140 2335);
DISPLAY INVISIBLE (-140 2335);
FORCEPROP 1 LASTPIN (-150 2325) BN 20
J 2
(-100 2335);
DISPLAY 0.617021 (-100 2335);
PAINT PINK (-100 2335);
FORCEPROP 2 LAST CDS_LIB mstr_standard
J 2
(-100 2325);
DISPLAY 0.787234 (-100 2325);
PAINT MONO (-100 2325);
DISPLAY INVISIBLE (-100 2325);
FORCEPROP 1 LAST BODY_TYPE PLUMBING
J 2
(-100 2275);
DISPLAY 1.234043 (-100 2275);
PAINT GREEN (-100 2275);
DISPLAY INVISIBLE (-100 2275);
FORCEPROP 1 LAST HDL_TAP TRUE
J 2
(-425 2200);
DISPLAY 1.234043 (-425 2200);
PAINT GREEN (-425 2200);
DISPLAY INVISIBLE (-425 2200);
FORCEPROP 1 LAST PATH I73
J 2
(-98 2325);
DISPLAY 0.872340 (-98 2325);
PAINT GREEN (-98 2325);
DISPLAY INVISIBLE (-98 2325);
FORCEADD TAP..6
R 2
(-100 2475);
FORCEPROP 3 LASTPIN (-150 2475) SIG_NAME M_K_DQ<23>
J 0
(-140 2485);
DISPLAY 0.659574 (-140 2485);
PAINT MONO (-140 2485);
DISPLAY INVISIBLE (-140 2485);
FORCEPROP 1 LASTPIN (-150 2475) BN 23
J 2
(-100 2485);
DISPLAY 0.617021 (-100 2485);
PAINT PINK (-100 2485);
FORCEPROP 2 LAST CDS_LIB mstr_standard
J 2
(-100 2475);
DISPLAY 0.787234 (-100 2475);
PAINT MONO (-100 2475);
DISPLAY INVISIBLE (-100 2475);
FORCEPROP 1 LAST BODY_TYPE PLUMBING
J 2
(-100 2425);
DISPLAY 1.234043 (-100 2425);
PAINT GREEN (-100 2425);
DISPLAY INVISIBLE (-100 2425);
FORCEPROP 1 LAST HDL_TAP TRUE
J 2
(-425 2350);
DISPLAY 1.234043 (-425 2350);
PAINT GREEN (-425 2350);
DISPLAY INVISIBLE (-425 2350);
FORCEPROP 1 LAST PATH I74
J 2
(-98 2475);
DISPLAY 0.872340 (-98 2475);
PAINT GREEN (-98 2475);
DISPLAY INVISIBLE (-98 2475);
FORCEADD TAP..6
R 2
(-100 2525);
FORCEPROP 3 LASTPIN (-150 2525) SIG_NAME M_K_DQ<24>
J 0
(-140 2535);
DISPLAY 0.659574 (-140 2535);
PAINT MONO (-140 2535);
DISPLAY INVISIBLE (-140 2535);
FORCEPROP 1 LASTPIN (-150 2525) BN 24
J 2
(-100 2535);
DISPLAY 0.617021 (-100 2535);
PAINT PINK (-100 2535);
FORCEPROP 2 LAST CDS_LIB mstr_standard
J 2
(-100 2525);
DISPLAY 0.787234 (-100 2525);
PAINT MONO (-100 2525);
DISPLAY INVISIBLE (-100 2525);
FORCEPROP 1 LAST BODY_TYPE PLUMBING
J 2
(-100 2475);
DISPLAY 1.234043 (-100 2475);
PAINT GREEN (-100 2475);
DISPLAY INVISIBLE (-100 2475);
FORCEPROP 1 LAST HDL_TAP TRUE
J 2
(-425 2400);
DISPLAY 1.234043 (-425 2400);
PAINT GREEN (-425 2400);
DISPLAY INVISIBLE (-425 2400);
FORCEPROP 1 LAST PATH I75
J 2
(-98 2525);
DISPLAY 0.872340 (-98 2525);
PAINT GREEN (-98 2525);
DISPLAY INVISIBLE (-98 2525);
FORCEADD TAP..6
R 2
(-100 2675);
FORCEPROP 3 LASTPIN (-150 2675) SIG_NAME M_K_DQ<27>
J 0
(-140 2685);
DISPLAY 0.659574 (-140 2685);
PAINT MONO (-140 2685);
DISPLAY INVISIBLE (-140 2685);
FORCEPROP 1 LASTPIN (-150 2675) BN 27
J 2
(-100 2685);
DISPLAY 0.617021 (-100 2685);
PAINT PINK (-100 2685);
FORCEPROP 2 LAST CDS_LIB mstr_standard
J 2
(-100 2675);
DISPLAY 0.787234 (-100 2675);
PAINT MONO (-100 2675);
DISPLAY INVISIBLE (-100 2675);
FORCEPROP 1 LAST BODY_TYPE PLUMBING
J 2
(-100 2625);
DISPLAY 1.234043 (-100 2625);
PAINT GREEN (-100 2625);
DISPLAY INVISIBLE (-100 2625);
FORCEPROP 1 LAST HDL_TAP TRUE
J 2
(-425 2550);
DISPLAY 1.234043 (-425 2550);
PAINT GREEN (-425 2550);
DISPLAY INVISIBLE (-425 2550);
FORCEPROP 1 LAST PATH I76
J 2
(-98 2675);
DISPLAY 0.872340 (-98 2675);
PAINT GREEN (-98 2675);
DISPLAY INVISIBLE (-98 2675);
FORCEADD TAP..6
R 2
(-100 2625);
FORCEPROP 3 LASTPIN (-150 2625) SIG_NAME M_K_DQ<26>
J 0
(-140 2635);
DISPLAY 0.659574 (-140 2635);
PAINT MONO (-140 2635);
DISPLAY INVISIBLE (-140 2635);
FORCEPROP 1 LASTPIN (-150 2625) BN 26
J 2
(-100 2635);
DISPLAY 0.617021 (-100 2635);
PAINT PINK (-100 2635);
FORCEPROP 2 LAST CDS_LIB mstr_standard
J 2
(-100 2625);
DISPLAY 0.787234 (-100 2625);
PAINT MONO (-100 2625);
DISPLAY INVISIBLE (-100 2625);
FORCEPROP 1 LAST BODY_TYPE PLUMBING
J 2
(-100 2575);
DISPLAY 1.234043 (-100 2575);
PAINT GREEN (-100 2575);
DISPLAY INVISIBLE (-100 2575);
FORCEPROP 1 LAST HDL_TAP TRUE
J 2
(-425 2500);
DISPLAY 1.234043 (-425 2500);
PAINT GREEN (-425 2500);
DISPLAY INVISIBLE (-425 2500);
FORCEPROP 1 LAST PATH I77
J 2
(-98 2625);
DISPLAY 0.872340 (-98 2625);
PAINT GREEN (-98 2625);
DISPLAY INVISIBLE (-98 2625);
FORCEADD TAP..6
R 2
(-100 2575);
FORCEPROP 3 LASTPIN (-150 2575) SIG_NAME M_K_DQ<25>
J 0
(-140 2585);
DISPLAY 0.659574 (-140 2585);
PAINT MONO (-140 2585);
DISPLAY INVISIBLE (-140 2585);
FORCEPROP 1 LASTPIN (-150 2575) BN 25
J 2
(-100 2585);
DISPLAY 0.617021 (-100 2585);
PAINT PINK (-100 2585);
FORCEPROP 2 LAST CDS_LIB mstr_standard
J 2
(-100 2575);
DISPLAY 0.787234 (-100 2575);
PAINT MONO (-100 2575);
DISPLAY INVISIBLE (-100 2575);
FORCEPROP 1 LAST BODY_TYPE PLUMBING
J 2
(-100 2525);
DISPLAY 1.234043 (-100 2525);
PAINT GREEN (-100 2525);
DISPLAY INVISIBLE (-100 2525);
FORCEPROP 1 LAST HDL_TAP TRUE
J 2
(-425 2450);
DISPLAY 1.234043 (-425 2450);
PAINT GREEN (-425 2450);
DISPLAY INVISIBLE (-425 2450);
FORCEPROP 1 LAST PATH I78
J 2
(-98 2575);
DISPLAY 0.872340 (-98 2575);
PAINT GREEN (-98 2575);
DISPLAY INVISIBLE (-98 2575);
FORCEADD PVDDQ_KLM..1
(325 2275);
FORCEPROP 3 LASTPIN (325 2225) SIG_NAME PVDDQ_KLM\g
J 0
(335 2235);
DISPLAY 0.659574 (335 2235);
PAINT MONO (335 2235);
DISPLAY INVISIBLE (335 2235);
FORCEPROP 1 LAST VOLTAGE 1.2V
J 0
(280 2232);
DISPLAY 0.340426 (280 2232);
PAINT SKYBLUE (280 2232);
DISPLAY INVISIBLE (280 2232);
FORCEPROP 2 LAST BOM_COST MEM
J 0
(325 2280);
PAINT ORANGE (325 2280);
DISPLAY INVISIBLE (325 2280);
FORCEPROP 2 LAST CDS_LIB mstr_symbols
J 0
(325 2275);
PAINT ORANGE (325 2275);
DISPLAY INVISIBLE (325 2275);
FORCEPROP 1 LAST BODY_TYPE PLUMBING
J 0
(280 2232);
DISPLAY 0.340426 (280 2232);
PAINT GREEN (280 2232);
DISPLAY INVISIBLE (280 2232);
FORCEPROP 1 LAST PATH I79
J 0
(375 2300);
DISPLAY 0.872340 (375 2300);
PAINT AQUA (375 2300);
DISPLAY INVISIBLE (375 2300);
FORCEPROP 2 LAST ROOM DDR4_CH_C
J 0
(325 2375);
DISPLAY 0.787234 (325 2375);
PAINT ORANGE (325 2375);
DISPLAY INVISIBLE (325 2375);
FORCEPROP 1 LAST HDL_POWER PVDDQ_KLM
J 1
(325 2325);
DISPLAY 0.872340 (325 2325);
PAINT GREEN (325 2325);
DISPLAY INVISIBLE (325 2325);
FORCEADD OFFPAGE..5
(-2575 2175);
FORCEPROP 2 LAST $XR23 94 
J 0
(-3189 2211);
DISPLAY 0.638298 (-3189 2211);
PAINT MONO (-3189 2211);
FORCEPROP 2 LAST $XR22 88 
J 0
(-3099 2211);
DISPLAY 0.638298 (-3099 2211);
PAINT MONO (-3099 2211);
FORCEPROP 2 LAST $XR21 87 
J 0
(-3009 2211);
DISPLAY 0.638298 (-3009 2211);
PAINT MONO (-3009 2211);
FORCEPROP 2 LAST $XR20 86 
J 0
(-2919 2211);
DISPLAY 0.638298 (-2919 2211);
PAINT MONO (-2919 2211);
FORCEPROP 2 LAST $XR19 85 
J 0
(-2829 2211);
DISPLAY 0.638298 (-2829 2211);
PAINT MONO (-2829 2211);
FORCEPROP 2 LAST $XR18 83 
J 0
(-3549 2139);
DISPLAY 0.638298 (-3549 2139);
PAINT MONO (-3549 2139);
FORCEPROP 2 LAST $XR17 82 
J 0
(-3459 2139);
DISPLAY 0.638298 (-3459 2139);
PAINT MONO (-3459 2139);
FORCEPROP 2 LAST $XR16 81 
J 0
(-3369 2139);
DISPLAY 0.638298 (-3369 2139);
PAINT MONO (-3369 2139);
FORCEPROP 2 LAST $XR15 80 
J 0
(-3279 2139);
DISPLAY 0.638298 (-3279 2139);
PAINT MONO (-3279 2139);
FORCEPROP 2 LAST $XR14 79 
J 0
(-3189 2139);
DISPLAY 0.638298 (-3189 2139);
PAINT MONO (-3189 2139);
FORCEPROP 2 LAST $XR13 78 
J 0
(-3099 2139);
DISPLAY 0.638298 (-3099 2139);
PAINT MONO (-3099 2139);
FORCEPROP 2 LAST $XR12 77 
J 0
(-3009 2139);
DISPLAY 0.638298 (-3009 2139);
PAINT MONO (-3009 2139);
FORCEPROP 2 LAST $XR11 54 
J 0
(-2919 2139);
DISPLAY 0.638298 (-2919 2139);
PAINT MONO (-2919 2139);
FORCEPROP 2 LAST $XR10 53 
J 0
(-2829 2139);
DISPLAY 0.638298 (-2829 2139);
PAINT MONO (-2829 2139);
FORCEPROP 2 LAST $XR9 52 
J 0
(-3639 2175);
DISPLAY 0.638298 (-3639 2175);
PAINT MONO (-3639 2175);
FORCEPROP 2 LAST $XR8 51 
J 0
(-3549 2175);
DISPLAY 0.638298 (-3549 2175);
PAINT MONO (-3549 2175);
FORCEPROP 2 LAST $XR7 50 
J 0
(-3459 2175);
DISPLAY 0.638298 (-3459 2175);
PAINT MONO (-3459 2175);
FORCEPROP 2 LAST $XR6 49 
J 0
(-3369 2175);
DISPLAY 0.638298 (-3369 2175);
PAINT MONO (-3369 2175);
FORCEPROP 2 LAST $XR5 48 
J 0
(-3279 2175);
DISPLAY 0.638298 (-3279 2175);
PAINT MONO (-3279 2175);
FORCEPROP 2 LAST $XR4 47 
J 0
(-3189 2175);
DISPLAY 0.638298 (-3189 2175);
PAINT MONO (-3189 2175);
FORCEPROP 2 LAST $XR3 46 
J 0
(-3099 2175);
DISPLAY 0.638298 (-3099 2175);
PAINT MONO (-3099 2175);
FORCEPROP 2 LAST $XR2 45 
J 0
(-3009 2175);
DISPLAY 0.638298 (-3009 2175);
PAINT MONO (-3009 2175);
FORCEPROP 2 LAST $XR1 44 
J 0
(-2919 2175);
DISPLAY 0.638298 (-2919 2175);
PAINT MONO (-2919 2175);
FORCEPROP 2 LAST $XR0 43 
J 0
(-2829 2175);
DISPLAY 0.638298 (-2829 2175);
PAINT MONO (-2829 2175);
FORCEPROP 2 LAST CDS_LIB mstr_standard
J 0
(-2575 2175);
DISPLAY 0.787234 (-2575 2175);
PAINT MONO (-2575 2175);
DISPLAY INVISIBLE (-2575 2175);
FORCEPROP 1 LAST OFFPAGE TRUE
J 0
(-2250 2050);
DISPLAY 1.404255 (-2250 2050);
PAINT GREEN (-2250 2050);
DISPLAY INVISIBLE (-2250 2050);
FORCEPROP 1 LAST COMMENT_BODY TRUE
J 0
(-2475 2100);
DISPLAY 1.404255 (-2475 2100);
PAINT GREEN (-2475 2100);
DISPLAY INVISIBLE (-2475 2100);
FORCEPROP 2 LAST PATH I8
J 0
(-2825 2225);
DISPLAY 1.021277 (-2825 2225);
PAINT ORANGE (-2825 2225);
DISPLAY INVISIBLE (-2825 2225);
FORCEADD TAP..6
R 2
(-100 2725);
FORCEPROP 3 LASTPIN (-150 2725) SIG_NAME M_K_DQ<28>
J 0
(-140 2735);
DISPLAY 0.659574 (-140 2735);
PAINT MONO (-140 2735);
DISPLAY INVISIBLE (-140 2735);
FORCEPROP 1 LASTPIN (-150 2725) BN 28
J 2
(-100 2735);
DISPLAY 0.617021 (-100 2735);
PAINT PINK (-100 2735);
FORCEPROP 2 LAST CDS_LIB mstr_standard
J 2
(-100 2725);
DISPLAY 0.787234 (-100 2725);
PAINT MONO (-100 2725);
DISPLAY INVISIBLE (-100 2725);
FORCEPROP 1 LAST BODY_TYPE PLUMBING
J 2
(-100 2675);
DISPLAY 1.234043 (-100 2675);
PAINT GREEN (-100 2675);
DISPLAY INVISIBLE (-100 2675);
FORCEPROP 1 LAST HDL_TAP TRUE
J 2
(-425 2600);
DISPLAY 1.234043 (-425 2600);
PAINT GREEN (-425 2600);
DISPLAY INVISIBLE (-425 2600);
FORCEPROP 1 LAST PATH I80
J 2
(-98 2725);
DISPLAY 0.872340 (-98 2725);
PAINT GREEN (-98 2725);
DISPLAY INVISIBLE (-98 2725);
FORCEADD TAP..6
R 2
(-100 2775);
FORCEPROP 3 LASTPIN (-150 2775) SIG_NAME M_K_DQ<29>
J 0
(-140 2785);
DISPLAY 0.659574 (-140 2785);
PAINT MONO (-140 2785);
DISPLAY INVISIBLE (-140 2785);
FORCEPROP 1 LASTPIN (-150 2775) BN 29
J 2
(-100 2785);
DISPLAY 0.617021 (-100 2785);
PAINT PINK (-100 2785);
FORCEPROP 2 LAST CDS_LIB mstr_standard
J 2
(-100 2775);
DISPLAY 0.787234 (-100 2775);
PAINT MONO (-100 2775);
DISPLAY INVISIBLE (-100 2775);
FORCEPROP 1 LAST BODY_TYPE PLUMBING
J 2
(-100 2725);
DISPLAY 1.234043 (-100 2725);
PAINT GREEN (-100 2725);
DISPLAY INVISIBLE (-100 2725);
FORCEPROP 1 LAST HDL_TAP TRUE
J 2
(-425 2650);
DISPLAY 1.234043 (-425 2650);
PAINT GREEN (-425 2650);
DISPLAY INVISIBLE (-425 2650);
FORCEPROP 1 LAST PATH I81
J 2
(-98 2775);
DISPLAY 0.872340 (-98 2775);
PAINT GREEN (-98 2775);
DISPLAY INVISIBLE (-98 2775);
FORCEADD TAP..6
R 2
(-100 2825);
FORCEPROP 3 LASTPIN (-150 2825) SIG_NAME M_K_DQ<30>
J 0
(-140 2835);
DISPLAY 0.659574 (-140 2835);
PAINT MONO (-140 2835);
DISPLAY INVISIBLE (-140 2835);
FORCEPROP 1 LASTPIN (-150 2825) BN 30
J 2
(-100 2835);
DISPLAY 0.617021 (-100 2835);
PAINT PINK (-100 2835);
FORCEPROP 2 LAST CDS_LIB mstr_standard
J 2
(-100 2825);
DISPLAY 0.787234 (-100 2825);
PAINT MONO (-100 2825);
DISPLAY INVISIBLE (-100 2825);
FORCEPROP 1 LAST BODY_TYPE PLUMBING
J 2
(-100 2775);
DISPLAY 1.234043 (-100 2775);
PAINT GREEN (-100 2775);
DISPLAY INVISIBLE (-100 2775);
FORCEPROP 1 LAST HDL_TAP TRUE
J 2
(-425 2700);
DISPLAY 1.234043 (-425 2700);
PAINT GREEN (-425 2700);
DISPLAY INVISIBLE (-425 2700);
FORCEPROP 1 LAST PATH I82
J 2
(-98 2825);
DISPLAY 0.872340 (-98 2825);
PAINT GREEN (-98 2825);
DISPLAY INVISIBLE (-98 2825);
FORCEADD TAP..6
R 2
(-100 2875);
FORCEPROP 3 LASTPIN (-150 2875) SIG_NAME M_K_DQ<31>
J 0
(-140 2885);
DISPLAY 0.659574 (-140 2885);
PAINT MONO (-140 2885);
DISPLAY INVISIBLE (-140 2885);
FORCEPROP 1 LASTPIN (-150 2875) BN 31
J 2
(-100 2885);
DISPLAY 0.617021 (-100 2885);
PAINT PINK (-100 2885);
FORCEPROP 2 LAST CDS_LIB mstr_standard
J 2
(-100 2875);
DISPLAY 0.787234 (-100 2875);
PAINT MONO (-100 2875);
DISPLAY INVISIBLE (-100 2875);
FORCEPROP 1 LAST BODY_TYPE PLUMBING
J 2
(-100 2825);
DISPLAY 1.234043 (-100 2825);
PAINT GREEN (-100 2825);
DISPLAY INVISIBLE (-100 2825);
FORCEPROP 1 LAST HDL_TAP TRUE
J 2
(-425 2750);
DISPLAY 1.234043 (-425 2750);
PAINT GREEN (-425 2750);
DISPLAY INVISIBLE (-425 2750);
FORCEPROP 1 LAST PATH I83
J 2
(-98 2875);
DISPLAY 0.872340 (-98 2875);
PAINT GREEN (-98 2875);
DISPLAY INVISIBLE (-98 2875);
FORCEADD TAP..6
R 2
(-100 2925);
FORCEPROP 3 LASTPIN (-150 2925) SIG_NAME M_K_DQ<32>
J 0
(-140 2935);
DISPLAY 0.659574 (-140 2935);
PAINT MONO (-140 2935);
DISPLAY INVISIBLE (-140 2935);
FORCEPROP 1 LASTPIN (-150 2925) BN 32
J 2
(-100 2935);
DISPLAY 0.617021 (-100 2935);
PAINT PINK (-100 2935);
FORCEPROP 2 LAST CDS_LIB mstr_standard
J 2
(-100 2925);
DISPLAY 0.787234 (-100 2925);
PAINT MONO (-100 2925);
DISPLAY INVISIBLE (-100 2925);
FORCEPROP 1 LAST BODY_TYPE PLUMBING
J 2
(-100 2875);
DISPLAY 1.234043 (-100 2875);
PAINT GREEN (-100 2875);
DISPLAY INVISIBLE (-100 2875);
FORCEPROP 1 LAST HDL_TAP TRUE
J 2
(-425 2800);
DISPLAY 1.234043 (-425 2800);
PAINT GREEN (-425 2800);
DISPLAY INVISIBLE (-425 2800);
FORCEPROP 1 LAST PATH I84
J 2
(-98 2925);
DISPLAY 0.872340 (-98 2925);
PAINT GREEN (-98 2925);
DISPLAY INVISIBLE (-98 2925);
FORCEADD TAP..6
R 2
(-100 2975);
FORCEPROP 3 LASTPIN (-150 2975) SIG_NAME M_K_DQ<33>
J 0
(-140 2985);
DISPLAY 0.659574 (-140 2985);
PAINT MONO (-140 2985);
DISPLAY INVISIBLE (-140 2985);
FORCEPROP 1 LASTPIN (-150 2975) BN 33
J 2
(-100 2985);
DISPLAY 0.617021 (-100 2985);
PAINT PINK (-100 2985);
FORCEPROP 2 LAST CDS_LIB mstr_standard
J 2
(-100 2975);
DISPLAY 0.787234 (-100 2975);
PAINT MONO (-100 2975);
DISPLAY INVISIBLE (-100 2975);
FORCEPROP 1 LAST BODY_TYPE PLUMBING
J 2
(-100 2925);
DISPLAY 1.234043 (-100 2925);
PAINT GREEN (-100 2925);
DISPLAY INVISIBLE (-100 2925);
FORCEPROP 1 LAST HDL_TAP TRUE
J 2
(-425 2850);
DISPLAY 1.234043 (-425 2850);
PAINT GREEN (-425 2850);
DISPLAY INVISIBLE (-425 2850);
FORCEPROP 1 LAST PATH I85
J 2
(-98 2975);
DISPLAY 0.872340 (-98 2975);
PAINT GREEN (-98 2975);
DISPLAY INVISIBLE (-98 2975);
FORCEADD TAP..6
R 2
(-100 3025);
FORCEPROP 3 LASTPIN (-150 3025) SIG_NAME M_K_DQ<34>
J 0
(-140 3035);
DISPLAY 0.659574 (-140 3035);
PAINT MONO (-140 3035);
DISPLAY INVISIBLE (-140 3035);
FORCEPROP 1 LASTPIN (-150 3025) BN 34
J 2
(-100 3035);
DISPLAY 0.617021 (-100 3035);
PAINT PINK (-100 3035);
FORCEPROP 2 LAST CDS_LIB mstr_standard
J 2
(-100 3025);
DISPLAY 0.787234 (-100 3025);
PAINT MONO (-100 3025);
DISPLAY INVISIBLE (-100 3025);
FORCEPROP 1 LAST BODY_TYPE PLUMBING
J 2
(-100 2975);
DISPLAY 1.234043 (-100 2975);
PAINT GREEN (-100 2975);
DISPLAY INVISIBLE (-100 2975);
FORCEPROP 1 LAST HDL_TAP TRUE
J 2
(-425 2900);
DISPLAY 1.234043 (-425 2900);
PAINT GREEN (-425 2900);
DISPLAY INVISIBLE (-425 2900);
FORCEPROP 1 LAST PATH I86
J 2
(-98 3025);
DISPLAY 0.872340 (-98 3025);
PAINT GREEN (-98 3025);
DISPLAY INVISIBLE (-98 3025);
FORCEADD TAP..6
R 2
(-100 3075);
FORCEPROP 3 LASTPIN (-150 3075) SIG_NAME M_K_DQ<35>
J 0
(-140 3085);
DISPLAY 0.659574 (-140 3085);
PAINT MONO (-140 3085);
DISPLAY INVISIBLE (-140 3085);
FORCEPROP 1 LASTPIN (-150 3075) BN 35
J 2
(-100 3085);
DISPLAY 0.617021 (-100 3085);
PAINT PINK (-100 3085);
FORCEPROP 2 LAST CDS_LIB mstr_standard
J 2
(-100 3075);
DISPLAY 0.787234 (-100 3075);
PAINT MONO (-100 3075);
DISPLAY INVISIBLE (-100 3075);
FORCEPROP 1 LAST BODY_TYPE PLUMBING
J 2
(-100 3025);
DISPLAY 1.234043 (-100 3025);
PAINT GREEN (-100 3025);
DISPLAY INVISIBLE (-100 3025);
FORCEPROP 1 LAST HDL_TAP TRUE
J 2
(-425 2950);
DISPLAY 1.234043 (-425 2950);
PAINT GREEN (-425 2950);
DISPLAY INVISIBLE (-425 2950);
FORCEPROP 1 LAST PATH I87
J 2
(-98 3075);
DISPLAY 0.872340 (-98 3075);
PAINT GREEN (-98 3075);
DISPLAY INVISIBLE (-98 3075);
FORCEADD TAP..6
R 2
(-100 3125);
FORCEPROP 3 LASTPIN (-150 3125) SIG_NAME M_K_DQ<36>
J 0
(-140 3135);
DISPLAY 0.659574 (-140 3135);
PAINT MONO (-140 3135);
DISPLAY INVISIBLE (-140 3135);
FORCEPROP 1 LASTPIN (-150 3125) BN 36
J 2
(-100 3135);
DISPLAY 0.617021 (-100 3135);
PAINT PINK (-100 3135);
FORCEPROP 2 LAST CDS_LIB mstr_standard
J 2
(-100 3125);
DISPLAY 0.787234 (-100 3125);
PAINT MONO (-100 3125);
DISPLAY INVISIBLE (-100 3125);
FORCEPROP 1 LAST BODY_TYPE PLUMBING
J 2
(-100 3075);
DISPLAY 1.234043 (-100 3075);
PAINT GREEN (-100 3075);
DISPLAY INVISIBLE (-100 3075);
FORCEPROP 1 LAST HDL_TAP TRUE
J 2
(-425 3000);
DISPLAY 1.234043 (-425 3000);
PAINT GREEN (-425 3000);
DISPLAY INVISIBLE (-425 3000);
FORCEPROP 1 LAST PATH I88
J 2
(-98 3125);
DISPLAY 0.872340 (-98 3125);
PAINT GREEN (-98 3125);
DISPLAY INVISIBLE (-98 3125);
FORCEADD TAP..6
R 2
(-100 3175);
FORCEPROP 3 LASTPIN (-150 3175) SIG_NAME M_K_DQ<37>
J 0
(-140 3185);
DISPLAY 0.659574 (-140 3185);
PAINT MONO (-140 3185);
DISPLAY INVISIBLE (-140 3185);
FORCEPROP 1 LASTPIN (-150 3175) BN 37
J 2
(-100 3185);
DISPLAY 0.617021 (-100 3185);
PAINT PINK (-100 3185);
FORCEPROP 2 LAST CDS_LIB mstr_standard
J 2
(-100 3175);
DISPLAY 0.787234 (-100 3175);
PAINT MONO (-100 3175);
DISPLAY INVISIBLE (-100 3175);
FORCEPROP 1 LAST BODY_TYPE PLUMBING
J 2
(-100 3125);
DISPLAY 1.234043 (-100 3125);
PAINT GREEN (-100 3125);
DISPLAY INVISIBLE (-100 3125);
FORCEPROP 1 LAST HDL_TAP TRUE
J 2
(-425 3050);
DISPLAY 1.234043 (-425 3050);
PAINT GREEN (-425 3050);
DISPLAY INVISIBLE (-425 3050);
FORCEPROP 1 LAST PATH I89
J 2
(-98 3175);
DISPLAY 0.872340 (-98 3175);
PAINT GREEN (-98 3175);
DISPLAY INVISIBLE (-98 3175);
FORCEADD OFFPAGE..1
(-2650 3375);
FORCEPROP 2 LAST $XR1 83 
J 0
(-2991 3375);
DISPLAY 0.638298 (-2991 3375);
PAINT MONO (-2991 3375);
FORCEPROP 2 LAST $XR0 60 
J 0
(-2901 3375);
DISPLAY 0.638298 (-2901 3375);
PAINT MONO (-2901 3375);
FORCEPROP 2 LAST CDS_LIB mstr_standard
J 0
(-2650 3375);
DISPLAY 0.787234 (-2650 3375);
PAINT MONO (-2650 3375);
DISPLAY INVISIBLE (-2650 3375);
FORCEPROP 1 LAST OFFPAGE TRUE
J 0
(-2325 3250);
DISPLAY 0.936170 (-2325 3250);
PAINT GREEN (-2325 3250);
DISPLAY INVISIBLE (-2325 3250);
FORCEPROP 1 LAST COMMENT_BODY TRUE
J 0
(-2525 3275);
DISPLAY 0.936170 (-2525 3275);
PAINT GREEN (-2525 3275);
DISPLAY INVISIBLE (-2525 3275);
FORCEPROP 2 LAST PATH I9
J 0
(-2900 3425);
DISPLAY 1.021277 (-2900 3425);
PAINT ORANGE (-2900 3425);
DISPLAY INVISIBLE (-2900 3425);
FORCEADD TAP..6
R 2
(-100 3225);
FORCEPROP 3 LASTPIN (-150 3225) SIG_NAME M_K_DQ<38>
J 0
(-140 3235);
DISPLAY 0.659574 (-140 3235);
PAINT MONO (-140 3235);
DISPLAY INVISIBLE (-140 3235);
FORCEPROP 1 LASTPIN (-150 3225) BN 38
J 2
(-100 3235);
DISPLAY 0.617021 (-100 3235);
PAINT PINK (-100 3235);
FORCEPROP 2 LAST CDS_LIB mstr_standard
J 2
(-100 3225);
DISPLAY 0.787234 (-100 3225);
PAINT MONO (-100 3225);
DISPLAY INVISIBLE (-100 3225);
FORCEPROP 1 LAST BODY_TYPE PLUMBING
J 2
(-100 3175);
DISPLAY 1.234043 (-100 3175);
PAINT GREEN (-100 3175);
DISPLAY INVISIBLE (-100 3175);
FORCEPROP 1 LAST HDL_TAP TRUE
J 2
(-425 3100);
DISPLAY 1.234043 (-425 3100);
PAINT GREEN (-425 3100);
DISPLAY INVISIBLE (-425 3100);
FORCEPROP 1 LAST PATH I90
J 2
(-98 3225);
DISPLAY 0.872340 (-98 3225);
PAINT GREEN (-98 3225);
DISPLAY INVISIBLE (-98 3225);
FORCEADD TAP..6
R 2
(-100 3325);
FORCEPROP 3 LASTPIN (-150 3325) SIG_NAME M_K_DQ<40>
J 0
(-140 3335);
DISPLAY 0.659574 (-140 3335);
PAINT MONO (-140 3335);
DISPLAY INVISIBLE (-140 3335);
FORCEPROP 1 LASTPIN (-150 3325) BN 40
J 2
(-100 3335);
DISPLAY 0.617021 (-100 3335);
PAINT PINK (-100 3335);
FORCEPROP 2 LAST CDS_LIB mstr_standard
J 2
(-100 3325);
DISPLAY 0.787234 (-100 3325);
PAINT MONO (-100 3325);
DISPLAY INVISIBLE (-100 3325);
FORCEPROP 1 LAST BODY_TYPE PLUMBING
J 2
(-100 3275);
DISPLAY 1.234043 (-100 3275);
PAINT GREEN (-100 3275);
DISPLAY INVISIBLE (-100 3275);
FORCEPROP 1 LAST HDL_TAP TRUE
J 2
(-425 3200);
DISPLAY 1.234043 (-425 3200);
PAINT GREEN (-425 3200);
DISPLAY INVISIBLE (-425 3200);
FORCEPROP 1 LAST PATH I91
J 2
(-98 3325);
DISPLAY 0.872340 (-98 3325);
PAINT GREEN (-98 3325);
DISPLAY INVISIBLE (-98 3325);
FORCEADD TAP..6
R 2
(-100 3275);
FORCEPROP 3 LASTPIN (-150 3275) SIG_NAME M_K_DQ<39>
J 0
(-140 3285);
DISPLAY 0.659574 (-140 3285);
PAINT MONO (-140 3285);
DISPLAY INVISIBLE (-140 3285);
FORCEPROP 1 LASTPIN (-150 3275) BN 39
J 2
(-100 3285);
DISPLAY 0.617021 (-100 3285);
PAINT PINK (-100 3285);
FORCEPROP 2 LAST CDS_LIB mstr_standard
J 2
(-100 3275);
DISPLAY 0.787234 (-100 3275);
PAINT MONO (-100 3275);
DISPLAY INVISIBLE (-100 3275);
FORCEPROP 1 LAST BODY_TYPE PLUMBING
J 2
(-100 3225);
DISPLAY 1.234043 (-100 3225);
PAINT GREEN (-100 3225);
DISPLAY INVISIBLE (-100 3225);
FORCEPROP 1 LAST HDL_TAP TRUE
J 2
(-425 3150);
DISPLAY 1.234043 (-425 3150);
PAINT GREEN (-425 3150);
DISPLAY INVISIBLE (-425 3150);
FORCEPROP 1 LAST PATH I92
J 2
(-98 3275);
DISPLAY 0.872340 (-98 3275);
PAINT GREEN (-98 3275);
DISPLAY INVISIBLE (-98 3275);
FORCEADD TAP..6
R 2
(-100 3425);
FORCEPROP 3 LASTPIN (-150 3425) SIG_NAME M_K_DQ<42>
J 0
(-140 3435);
DISPLAY 0.659574 (-140 3435);
PAINT MONO (-140 3435);
DISPLAY INVISIBLE (-140 3435);
FORCEPROP 1 LASTPIN (-150 3425) BN 42
J 2
(-100 3435);
DISPLAY 0.617021 (-100 3435);
PAINT PINK (-100 3435);
FORCEPROP 2 LAST CDS_LIB mstr_standard
J 2
(-100 3425);
DISPLAY 0.787234 (-100 3425);
PAINT MONO (-100 3425);
DISPLAY INVISIBLE (-100 3425);
FORCEPROP 1 LAST BODY_TYPE PLUMBING
J 2
(-100 3375);
DISPLAY 1.234043 (-100 3375);
PAINT GREEN (-100 3375);
DISPLAY INVISIBLE (-100 3375);
FORCEPROP 1 LAST HDL_TAP TRUE
J 2
(-425 3300);
DISPLAY 1.234043 (-425 3300);
PAINT GREEN (-425 3300);
DISPLAY INVISIBLE (-425 3300);
FORCEPROP 1 LAST PATH I93
J 2
(-98 3425);
DISPLAY 0.872340 (-98 3425);
PAINT GREEN (-98 3425);
DISPLAY INVISIBLE (-98 3425);
FORCEADD TAP..6
R 2
(-100 3375);
FORCEPROP 3 LASTPIN (-150 3375) SIG_NAME M_K_DQ<41>
J 0
(-140 3385);
DISPLAY 0.659574 (-140 3385);
PAINT MONO (-140 3385);
DISPLAY INVISIBLE (-140 3385);
FORCEPROP 1 LASTPIN (-150 3375) BN 41
J 2
(-100 3385);
DISPLAY 0.617021 (-100 3385);
PAINT PINK (-100 3385);
FORCEPROP 2 LAST CDS_LIB mstr_standard
J 2
(-100 3375);
DISPLAY 0.787234 (-100 3375);
PAINT MONO (-100 3375);
DISPLAY INVISIBLE (-100 3375);
FORCEPROP 1 LAST BODY_TYPE PLUMBING
J 2
(-100 3325);
DISPLAY 1.234043 (-100 3325);
PAINT GREEN (-100 3325);
DISPLAY INVISIBLE (-100 3325);
FORCEPROP 1 LAST HDL_TAP TRUE
J 2
(-425 3250);
DISPLAY 1.234043 (-425 3250);
PAINT GREEN (-425 3250);
DISPLAY INVISIBLE (-425 3250);
FORCEPROP 1 LAST PATH I94
J 2
(-98 3375);
DISPLAY 0.872340 (-98 3375);
PAINT GREEN (-98 3375);
DISPLAY INVISIBLE (-98 3375);
FORCEADD TAP..6
R 2
(-100 3475);
FORCEPROP 3 LASTPIN (-150 3475) SIG_NAME M_K_DQ<43>
J 0
(-140 3485);
DISPLAY 0.659574 (-140 3485);
PAINT MONO (-140 3485);
DISPLAY INVISIBLE (-140 3485);
FORCEPROP 1 LASTPIN (-150 3475) BN 43
J 2
(-100 3485);
DISPLAY 0.617021 (-100 3485);
PAINT PINK (-100 3485);
FORCEPROP 2 LAST CDS_LIB mstr_standard
J 2
(-100 3475);
DISPLAY 0.787234 (-100 3475);
PAINT MONO (-100 3475);
DISPLAY INVISIBLE (-100 3475);
FORCEPROP 1 LAST BODY_TYPE PLUMBING
J 2
(-100 3425);
DISPLAY 1.234043 (-100 3425);
PAINT GREEN (-100 3425);
DISPLAY INVISIBLE (-100 3425);
FORCEPROP 1 LAST HDL_TAP TRUE
J 2
(-425 3350);
DISPLAY 1.234043 (-425 3350);
PAINT GREEN (-425 3350);
DISPLAY INVISIBLE (-425 3350);
FORCEPROP 1 LAST PATH I95
J 2
(-98 3475);
DISPLAY 0.872340 (-98 3475);
PAINT GREEN (-98 3475);
DISPLAY INVISIBLE (-98 3475);
FORCEADD TAP..6
R 2
(-100 3575);
FORCEPROP 3 LASTPIN (-150 3575) SIG_NAME M_K_DQ<45>
J 0
(-140 3585);
DISPLAY 0.659574 (-140 3585);
PAINT MONO (-140 3585);
DISPLAY INVISIBLE (-140 3585);
FORCEPROP 1 LASTPIN (-150 3575) BN 45
J 2
(-100 3585);
DISPLAY 0.617021 (-100 3585);
PAINT PINK (-100 3585);
FORCEPROP 2 LAST CDS_LIB mstr_standard
J 2
(-100 3575);
DISPLAY 0.787234 (-100 3575);
PAINT MONO (-100 3575);
DISPLAY INVISIBLE (-100 3575);
FORCEPROP 1 LAST BODY_TYPE PLUMBING
J 2
(-100 3525);
DISPLAY 1.234043 (-100 3525);
PAINT GREEN (-100 3525);
DISPLAY INVISIBLE (-100 3525);
FORCEPROP 1 LAST HDL_TAP TRUE
J 2
(-425 3450);
DISPLAY 1.234043 (-425 3450);
PAINT GREEN (-425 3450);
DISPLAY INVISIBLE (-425 3450);
FORCEPROP 1 LAST PATH I96
J 2
(-98 3575);
DISPLAY 0.872340 (-98 3575);
PAINT GREEN (-98 3575);
DISPLAY INVISIBLE (-98 3575);
FORCEADD TAP..6
R 2
(-100 3525);
FORCEPROP 3 LASTPIN (-150 3525) SIG_NAME M_K_DQ<44>
J 0
(-140 3535);
DISPLAY 0.659574 (-140 3535);
PAINT MONO (-140 3535);
DISPLAY INVISIBLE (-140 3535);
FORCEPROP 1 LASTPIN (-150 3525) BN 44
J 2
(-100 3535);
DISPLAY 0.617021 (-100 3535);
PAINT PINK (-100 3535);
FORCEPROP 2 LAST CDS_LIB mstr_standard
J 2
(-100 3525);
DISPLAY 0.787234 (-100 3525);
PAINT MONO (-100 3525);
DISPLAY INVISIBLE (-100 3525);
FORCEPROP 1 LAST BODY_TYPE PLUMBING
J 2
(-100 3475);
DISPLAY 1.234043 (-100 3475);
PAINT GREEN (-100 3475);
DISPLAY INVISIBLE (-100 3475);
FORCEPROP 1 LAST HDL_TAP TRUE
J 2
(-425 3400);
DISPLAY 1.234043 (-425 3400);
PAINT GREEN (-425 3400);
DISPLAY INVISIBLE (-425 3400);
FORCEPROP 1 LAST PATH I97
J 2
(-98 3525);
DISPLAY 0.872340 (-98 3525);
PAINT GREEN (-98 3525);
DISPLAY INVISIBLE (-98 3525);
FORCEADD TAP..6
R 2
(-100 3675);
FORCEPROP 3 LASTPIN (-150 3675) SIG_NAME M_K_DQ<47>
J 0
(-140 3685);
DISPLAY 0.659574 (-140 3685);
PAINT MONO (-140 3685);
DISPLAY INVISIBLE (-140 3685);
FORCEPROP 1 LASTPIN (-150 3675) BN 47
J 2
(-100 3685);
DISPLAY 0.617021 (-100 3685);
PAINT PINK (-100 3685);
FORCEPROP 2 LAST CDS_LIB mstr_standard
J 2
(-100 3675);
DISPLAY 0.787234 (-100 3675);
PAINT MONO (-100 3675);
DISPLAY INVISIBLE (-100 3675);
FORCEPROP 1 LAST BODY_TYPE PLUMBING
J 2
(-100 3625);
DISPLAY 1.234043 (-100 3625);
PAINT GREEN (-100 3625);
DISPLAY INVISIBLE (-100 3625);
FORCEPROP 1 LAST HDL_TAP TRUE
J 2
(-425 3550);
DISPLAY 1.234043 (-425 3550);
PAINT GREEN (-425 3550);
DISPLAY INVISIBLE (-425 3550);
FORCEPROP 1 LAST PATH I98
J 2
(-98 3675);
DISPLAY 0.872340 (-98 3675);
PAINT GREEN (-98 3675);
DISPLAY INVISIBLE (-98 3675);
FORCEADD TAP..6
R 2
(-100 3625);
FORCEPROP 3 LASTPIN (-150 3625) SIG_NAME M_K_DQ<46>
J 0
(-140 3635);
DISPLAY 0.659574 (-140 3635);
PAINT MONO (-140 3635);
DISPLAY INVISIBLE (-140 3635);
FORCEPROP 1 LASTPIN (-150 3625) BN 46
J 2
(-100 3635);
DISPLAY 0.617021 (-100 3635);
PAINT PINK (-100 3635);
FORCEPROP 2 LAST CDS_LIB mstr_standard
J 2
(-100 3625);
DISPLAY 0.787234 (-100 3625);
PAINT MONO (-100 3625);
DISPLAY INVISIBLE (-100 3625);
FORCEPROP 1 LAST BODY_TYPE PLUMBING
J 2
(-100 3575);
DISPLAY 1.234043 (-100 3575);
PAINT GREEN (-100 3575);
DISPLAY INVISIBLE (-100 3575);
FORCEPROP 1 LAST HDL_TAP TRUE
J 2
(-425 3500);
DISPLAY 1.234043 (-425 3500);
PAINT GREEN (-425 3500);
DISPLAY INVISIBLE (-425 3500);
FORCEPROP 1 LAST PATH I99
J 2
(-98 3625);
DISPLAY 0.872340 (-98 3625);
PAINT GREEN (-98 3625);
DISPLAY INVISIBLE (-98 3625);
FORCEADD INTEL_CORP_BPAGE..1
(4250 200);
FORCEPROP 1 LAST CDS_CON_LAST_MODIFIED Fri Jun 16 17:48:31 2017
J 0
(2825 525);
PAINT ORANGE (2825 525);
DISPLAY INVISIBLE (2825 525);
FORCEPROP 1 LAST CUSTOM_TXT_CDS <CURRENT_DESIGN_SHEET> OF <TOTAL_DESIGN_SHEETS>
J 0
(3750 225);
PAINT ORANGE (3750 225);
FORCEPROP 1 LAST CUSTOM_TXT_CDS <CON_LAST_MODIFIED>
J 0
(250 300);
PAINT ORANGE (250 300);
FORCEPROP 2 LAST CUSTOM_TXT_CDS <XR_PAGE_TITLE>
J 0
(-3640 5450);
DISPLAY 0.638298 (-3640 5450);
PAINT PINK (-3640 5450);
DISPLAY INVISIBLE (-3640 5450);
FORCEPROP 1 LAST SCH_TITLE CPU1 DDR4 CH K DIMM1
J 0
(-3700 250);
DISPLAY 1.212766 (-3700 250);
PAINT ORANGE (-3700 250);
FORCEPROP 2 LAST CDS_LIB mstr_symbols
J 0
(4250 200);
PAINT MONO (4250 200);
DISPLAY INVISIBLE (4250 200);
FORCEPROP 2 LAST PAGE_BORDER TRUE
J 0
(-3640 5450);
DISPLAY 0.638298 (-3640 5450);
PAINT PINK (-3640 5450);
DISPLAY INVISIBLE (-3640 5450);
FORCEPROP 1 LAST COMMENT_BODY TRUE
J 0
(4262 212);
DISPLAY 0.468085 (4262 212);
PAINT GREEN (4262 212);
DISPLAY INVISIBLE (4262 212);
FORCEPROP 2 LAST CDS_XR_PAGE_TITLE CR-84 : @BASEBOARD_FAB2_LIB.BASEBOARD_FAB2(SCH_1):PAGE84
J 0
(-3640 5450);
DISPLAY 0.638298 (-3640 5450);
PAINT PINK (-3640 5450);
DISPLAY INVISIBLE (-3640 5450);
FORCEADD BOM_NOTE..1
(-3375 4975);
FORCEPROP 0 LAST L1 UNSTUFF FOR SKU B
J 0
(-3525 4875);
DISPLAY 1.063830 (-3525 4875);
PAINT WHITE (-3525 4875);
FORCEPROP 2 LAST BOM_COST SB
J 0
(-3525 4950);
DISPLAY 1.361702 (-3525 4950);
PAINT ORANGE (-3525 4950);
DISPLAY INVISIBLE (-3525 4950);
FORCEPROP 2 LAST CDS_LIB mstr_symbols
J 0
(-3375 4975);
PAINT ORANGE (-3375 4975);
DISPLAY INVISIBLE (-3375 4975);
FORCEPROP 1 LAST COMMENT_BODY TRUE
J 0
(-3350 5075);
DISPLAY 1.319149 (-3350 5075);
PAINT ORANGE (-3350 5075);
DISPLAY INVISIBLE (-3350 5075);
FORCEPROP 2 LAST ROOM SB_HEADERS
J 0
(-3525 4950);
DISPLAY 1.361702 (-3525 4950);
PAINT ORANGE (-3525 4950);
DISPLAY INVISIBLE (-3525 4950);
WIRE 16 -1 (-3500 1625)(-3500 1525);
WIRE 16 -1 (-3500 1625)(-1500 1625);
WIRE 16 -1 (-1500 1625)(-1500 1575);
WIRE 16 -1 (-1500 1625)(-1350 1625);
WIRE 16 -1 (-1350 1575)(-1500 1575);
WIRE 16 -1 (600 2375)(600 2275);
WIRE 16 -1 (600 2275)(750 2275);
WIRE 16 -1 (750 2225)(750 2275);
WIRE 16 -1 (750 2275)(950 2275);
WIRE 16 -1 (750 2225)(950 2225);
WIRE 16 -1 (750 2675)(750 2575);
WIRE 16 -1 (750 2575)(750 2525);
WIRE 16 -1 (750 2575)(950 2575);
WIRE 16 -1 (750 2475)(750 2525);
WIRE 16 -1 (750 2525)(950 2525);
WIRE 16 -1 (750 2475)(750 2425);
WIRE 16 -1 (750 2475)(950 2475);
WIRE 16 -1 (750 2425)(750 2375);
WIRE 16 -1 (750 2425)(950 2425);
WIRE 16 -1 (750 2375)(950 2375);
WIRE 16 -1 (2700 775)(2700 875);
WIRE 16 -1 (2700 875)(2700 925);
WIRE 16 -1 (2700 875)(2900 875);
WIRE 16 -1 (2700 925)(2700 975);
WIRE 16 -1 (2700 925)(2900 925);
WIRE 16 -1 (2700 975)(2700 1025);
WIRE 16 -1 (2700 975)(2900 975);
WIRE 16 -1 (2700 1025)(2700 1075);
WIRE 16 -1 (2700 1025)(2900 1025);
WIRE 16 -1 (2700 1075)(2700 1125);
WIRE 16 -1 (2700 1075)(2900 1075);
WIRE 16 -1 (2700 1125)(2700 1175);
WIRE 16 -1 (2700 1125)(2900 1125);
WIRE 16 -1 (2700 1175)(2700 1225);
WIRE 16 -1 (2700 1175)(2900 1175);
WIRE 16 -1 (2700 1225)(2700 1275);
WIRE 16 -1 (2700 1225)(2900 1225);
WIRE 16 -1 (2700 1275)(2700 1325);
WIRE 16 -1 (2700 1275)(2900 1275);
WIRE 16 -1 (2700 1325)(2700 1375);
WIRE 16 -1 (2700 1325)(2900 1325);
WIRE 16 -1 (2700 1375)(2700 1425);
WIRE 16 -1 (2700 1375)(2900 1375);
WIRE 16 -1 (2700 1425)(2700 1475);
WIRE 16 -1 (2700 1425)(2900 1425);
WIRE 16 -1 (2700 1475)(2700 1525);
WIRE 16 -1 (2700 1475)(2900 1475);
WIRE 16 -1 (2700 1525)(2700 1575);
WIRE 16 -1 (2700 1525)(2900 1525);
WIRE 16 -1 (2700 1575)(2700 1625);
WIRE 16 -1 (2700 1575)(2900 1575);
WIRE 16 -1 (2700 1625)(2700 1675);
WIRE 16 -1 (2700 1625)(2900 1625);
WIRE 16 -1 (2700 1675)(2700 1725);
WIRE 16 -1 (2700 1675)(2900 1675);
WIRE 16 -1 (2700 1725)(2700 1775);
WIRE 16 -1 (2700 1725)(2900 1725);
WIRE 16 -1 (2700 1775)(2700 1825);
WIRE 16 -1 (2700 1775)(2900 1775);
WIRE 16 -1 (2700 1825)(2700 1875);
WIRE 16 -1 (2700 1825)(2900 1825);
WIRE 16 -1 (2700 1875)(2700 1925);
WIRE 16 -1 (2700 1875)(2900 1875);
WIRE 16 -1 (2700 1925)(2700 1975);
WIRE 16 -1 (2700 1925)(2900 1925);
WIRE 16 -1 (2700 1975)(2700 2025);
WIRE 16 -1 (2700 1975)(2900 1975);
WIRE 16 -1 (2700 2025)(2700 2075);
WIRE 16 -1 (2700 2025)(2900 2025);
WIRE 16 -1 (2700 2075)(2700 2125);
WIRE 16 -1 (2700 2075)(2900 2075);
WIRE 16 -1 (2700 2125)(2700 2175);
WIRE 16 -1 (2700 2125)(2900 2125);
WIRE 16 -1 (2700 2175)(2700 2225);
WIRE 16 -1 (2700 2175)(2900 2175);
WIRE 16 -1 (2700 2225)(2700 2275);
WIRE 16 -1 (2700 2225)(2900 2225);
WIRE 16 -1 (2700 2275)(2700 2325);
WIRE 16 -1 (2700 2275)(2900 2275);
WIRE 16 -1 (2700 2325)(2700 2375);
WIRE 16 -1 (2700 2325)(2900 2325);
WIRE 16 -1 (2700 2375)(2700 2425);
WIRE 16 -1 (2700 2375)(2900 2375);
WIRE 16 -1 (2700 2425)(2700 2475);
WIRE 16 -1 (2700 2425)(2900 2425);
WIRE 16 -1 (2700 2475)(2700 2525);
WIRE 16 -1 (2700 2475)(2900 2475);
WIRE 16 -1 (2700 2525)(2700 2575);
WIRE 16 -1 (2700 2525)(2900 2525);
WIRE 16 -1 (2700 2575)(2700 2625);
WIRE 16 -1 (2700 2575)(2900 2575);
WIRE 16 -1 (2700 2625)(2700 2675);
WIRE 16 -1 (2700 2625)(2900 2625);
WIRE 16 -1 (2700 2675)(2700 2725);
WIRE 16 -1 (2700 2675)(2900 2675);
WIRE 16 -1 (2700 2725)(2700 2775);
WIRE 16 -1 (2700 2725)(2900 2725);
WIRE 16 -1 (2700 2775)(2700 2825);
WIRE 16 -1 (2700 2775)(2900 2775);
WIRE 16 -1 (2700 2825)(2700 2875);
WIRE 16 -1 (2700 2825)(2900 2825);
WIRE 16 -1 (2700 2875)(2700 2925);
WIRE 16 -1 (2700 2875)(2900 2875);
WIRE 16 -1 (2700 2925)(2700 2975);
WIRE 16 -1 (2700 2925)(2900 2925);
WIRE 16 -1 (2700 2975)(2700 3025);
WIRE 16 -1 (2700 2975)(2900 2975);
WIRE 16 -1 (2700 3025)(2700 3075);
WIRE 16 -1 (2700 3025)(2900 3025);
WIRE 16 -1 (2700 3075)(2700 3125);
WIRE 16 -1 (2700 3075)(2900 3075);
WIRE 16 -1 (2700 3125)(2700 3175);
WIRE 16 -1 (2700 3125)(2900 3125);
WIRE 16 -1 (2700 3175)(2900 3175);
WIRE 16 -1 (4100 775)(4100 875);
WIRE 16 -1 (4100 875)(4100 925);
WIRE 16 -1 (4100 875)(3900 875);
WIRE 16 -1 (4100 925)(4100 975);
WIRE 16 -1 (4100 925)(3900 925);
WIRE 16 -1 (4100 975)(4100 1025);
WIRE 16 -1 (4100 975)(3900 975);
WIRE 16 -1 (4100 1025)(4100 1075);
WIRE 16 -1 (4100 1025)(3900 1025);
WIRE 16 -1 (4100 1075)(4100 1125);
WIRE 16 -1 (4100 1075)(3900 1075);
WIRE 16 -1 (4100 1125)(4100 1175);
WIRE 16 -1 (4100 1125)(3900 1125);
WIRE 16 -1 (4100 1175)(4100 1225);
WIRE 16 -1 (4100 1175)(3900 1175);
WIRE 16 -1 (4100 1225)(4100 1275);
WIRE 16 -1 (4100 1225)(3900 1225);
WIRE 16 -1 (4100 1275)(4100 1325);
WIRE 16 -1 (4100 1275)(3900 1275);
WIRE 16 -1 (4100 1325)(4100 1375);
WIRE 16 -1 (4100 1325)(3900 1325);
WIRE 16 -1 (4100 1375)(4100 1425);
WIRE 16 -1 (4100 1375)(3900 1375);
WIRE 16 -1 (4100 1425)(4100 1475);
WIRE 16 -1 (4100 1425)(3900 1425);
WIRE 16 -1 (4100 1475)(4100 1525);
WIRE 16 -1 (4100 1475)(3900 1475);
WIRE 16 -1 (4100 1525)(4100 1575);
WIRE 16 -1 (4100 1525)(3900 1525);
WIRE 16 -1 (4100 1575)(4100 1625);
WIRE 16 -1 (4100 1575)(3900 1575);
WIRE 16 -1 (4100 1625)(4100 1675);
WIRE 16 -1 (4100 1625)(3900 1625);
WIRE 16 -1 (4100 1675)(4100 1725);
WIRE 16 -1 (4100 1675)(3900 1675);
WIRE 16 -1 (4100 1725)(4100 1775);
WIRE 16 -1 (4100 1725)(3900 1725);
WIRE 16 -1 (4100 1775)(4100 1825);
WIRE 16 -1 (4100 1775)(3900 1775);
WIRE 16 -1 (4100 1825)(4100 1875);
WIRE 16 -1 (4100 1825)(3900 1825);
WIRE 16 -1 (4100 1875)(4100 1925);
WIRE 16 -1 (4100 1875)(3900 1875);
WIRE 16 -1 (4100 1925)(4100 1975);
WIRE 16 -1 (4100 1925)(3900 1925);
WIRE 16 -1 (4100 1975)(4100 2025);
WIRE 16 -1 (4100 1975)(3900 1975);
WIRE 16 -1 (4100 2025)(4100 2075);
WIRE 16 -1 (4100 2025)(3900 2025);
WIRE 16 -1 (4100 2075)(4100 2125);
WIRE 16 -1 (4100 2075)(3900 2075);
WIRE 16 -1 (4100 2125)(4100 2175);
WIRE 16 -1 (4100 2125)(3900 2125);
WIRE 16 -1 (4100 2175)(4100 2225);
WIRE 16 -1 (4100 2175)(3900 2175);
WIRE 16 -1 (4100 2225)(4100 2275);
WIRE 16 -1 (4100 2225)(3900 2225);
WIRE 16 -1 (4100 2275)(4100 2325);
WIRE 16 -1 (4100 2275)(3900 2275);
WIRE 16 -1 (4100 2325)(4100 2375);
WIRE 16 -1 (4100 2325)(3900 2325);
WIRE 16 -1 (4100 2375)(4100 2425);
WIRE 16 -1 (4100 2375)(3900 2375);
WIRE 16 -1 (4100 2425)(4100 2475);
WIRE 16 -1 (4100 2425)(3900 2425);
WIRE 16 -1 (4100 2475)(4100 2525);
WIRE 16 -1 (4100 2475)(3900 2475);
WIRE 16 -1 (4100 2525)(4100 2575);
WIRE 16 -1 (4100 2525)(3900 2525);
WIRE 16 -1 (4100 2575)(4100 2625);
WIRE 16 -1 (4100 2575)(3900 2575);
WIRE 16 -1 (4100 2625)(4100 2675);
WIRE 16 -1 (4100 2625)(3900 2625);
WIRE 16 -1 (4100 2675)(4100 2725);
WIRE 16 -1 (4100 2675)(3900 2675);
WIRE 16 -1 (4100 2725)(4100 2775);
WIRE 16 -1 (4100 2725)(3900 2725);
WIRE 16 -1 (4100 2775)(4100 2825);
WIRE 16 -1 (4100 2775)(3900 2775);
WIRE 16 -1 (4100 2825)(4100 2875);
WIRE 16 -1 (4100 2825)(3900 2825);
WIRE 16 -1 (4100 2875)(4100 2925);
WIRE 16 -1 (4100 2875)(3900 2875);
WIRE 16 -1 (4100 2925)(4100 2975);
WIRE 16 -1 (4100 2925)(3900 2925);
WIRE 16 -1 (4100 2975)(4100 3025);
WIRE 16 -1 (4100 2975)(3900 2975);
WIRE 16 -1 (4100 3025)(4100 3075);
WIRE 16 -1 (4100 3025)(3900 3025);
WIRE 16 -1 (4100 3075)(4100 3125);
WIRE 16 -1 (4100 3075)(3900 3075);
WIRE 16 -1 (4100 3125)(4100 3175);
WIRE 16 -1 (4100 3125)(3900 3125);
WIRE 16 -1 (4100 3175)(3900 3175);
WIRE 16 -1 (2150 2575)(2150 2750);
WIRE 16 -1 (2150 2525)(2150 2575);
WIRE 16 -1 (2150 2575)(1950 2575);
WIRE 16 -1 (2150 2525)(1950 2525);
WIRE 16 -1 (-3000 1025)(-3000 925);
WIRE 16 -1 (-3500 1675)(-3500 1775);
WIRE 16 -1 (-3500 1675)(-1550 1675);
WIRE 16 -1 (-1550 1525)(-1550 1675);
WIRE 16 -1 (-1550 1675)(-1350 1675);
WIRE 16 -1 (-1350 1525)(-1550 1525);
WIRE 16 -1 (325 2225)(325 2125);
WIRE 16 -1 (325 2125)(750 2125);
WIRE 16 -1 (750 2075)(750 2125);
WIRE 16 -1 (750 2125)(950 2125);
WIRE 16 -1 (750 2025)(750 2075);
WIRE 16 -1 (750 2075)(950 2075);
WIRE 16 -1 (750 1975)(750 2025);
WIRE 16 -1 (750 2025)(950 2025);
WIRE 16 -1 (750 1925)(750 1975);
WIRE 16 -1 (750 1975)(950 1975);
WIRE 16 -1 (750 1875)(750 1925);
WIRE 16 -1 (750 1925)(950 1925);
WIRE 16 -1 (750 1825)(750 1875);
WIRE 16 -1 (750 1875)(950 1875);
WIRE 16 -1 (750 1775)(750 1825);
WIRE 16 -1 (750 1825)(950 1825);
WIRE 16 -1 (750 1725)(750 1775);
WIRE 16 -1 (750 1775)(950 1775);
WIRE 16 -1 (750 1675)(750 1725);
WIRE 16 -1 (750 1725)(950 1725);
WIRE 16 -1 (750 1625)(750 1675);
WIRE 16 -1 (750 1675)(950 1675);
WIRE 16 -1 (750 1575)(750 1625);
WIRE 16 -1 (750 1625)(950 1625);
WIRE 16 -1 (750 1525)(750 1575);
WIRE 16 -1 (750 1575)(950 1575);
WIRE 16 -1 (750 1475)(750 1525);
WIRE 16 -1 (750 1525)(950 1525);
WIRE 16 -1 (750 1425)(750 1475);
WIRE 16 -1 (750 1475)(950 1475);
WIRE 16 -1 (750 1375)(750 1425);
WIRE 16 -1 (750 1425)(950 1425);
WIRE 16 -1 (750 1325)(750 1375);
WIRE 16 -1 (750 1375)(950 1375);
WIRE 16 -1 (750 1275)(750 1325);
WIRE 16 -1 (750 1325)(950 1325);
WIRE 16 -1 (750 1225)(750 1275);
WIRE 16 -1 (750 1275)(950 1275);
WIRE 16 -1 (750 1175)(750 1225);
WIRE 16 -1 (750 1225)(950 1225);
WIRE 16 -1 (750 1125)(750 1175);
WIRE 16 -1 (750 1175)(950 1175);
WIRE 16 -1 (750 1075)(750 1125);
WIRE 16 -1 (750 1125)(950 1125);
WIRE 16 -1 (750 1025)(750 1075);
WIRE 16 -1 (750 1075)(950 1075);
WIRE 16 -1 (750 975)(750 1025);
WIRE 16 -1 (750 1025)(950 1025);
WIRE 16 -1 (750 925)(750 975);
WIRE 16 -1 (750 975)(950 975);
WIRE 16 -1 (750 875)(750 925);
WIRE 16 -1 (750 925)(950 925);
WIRE 16 -1 (750 875)(950 875);
WIRE 17 -1 (2550 3100)(2550 3200);
WIRE 17 -1 (2550 3200)(2550 3300);
WIRE 17 -1 (2550 3300)(2550 3400);
WIRE 17 -1 (2550 3400)(2550 3500);
WIRE 17 -1 (2550 3500)(2550 3600);
WIRE 17 -1 (2550 3600)(2550 3700);
WIRE 17 -1 (2550 3700)(2550 3800);
WIRE 17 -1 (2550 3800)(2550 3900);
WIRE 17 -1 (2550 3900)(2550 4000);
WIRE 17 -1 (2550 4000)(2550 4100);
WIRE 17 -1 (2550 4100)(2550 4200);
WIRE 17 -1 (2550 4200)(2550 4300);
WIRE 17 -1 (2550 4300)(2550 4400);
WIRE 17 -1 (2550 4400)(2550 4500);
WIRE 17 -1 (2550 4500)(2550 4600);
WIRE 17 -1 (2550 4600)(2550 4700);
WIRE 17 -1 (3150 4825)(2550 4825);
FORCEPROP 2 LAST SIG_NAME M_K_DQS_DN<17:0>
J 0
(2600 4835);
DISPLAY 0.617021 (2600 4835);
PAINT ORANGE (2600 4835);
WIRE 17 -1 (2550 4700)(2550 4800);
WIRE 17 -1 (2550 4800)(2550 4825);
WIRE 17 -1 (2350 3150)(2350 3250);
WIRE 17 -1 (2350 3250)(2350 3350);
WIRE 17 -1 (2350 3350)(2350 3450);
WIRE 17 -1 (2350 3450)(2350 3550);
WIRE 17 -1 (2350 3550)(2350 3650);
WIRE 17 -1 (2350 3650)(2350 3750);
WIRE 17 -1 (2350 3750)(2350 3850);
WIRE 17 -1 (2350 3850)(2350 3950);
WIRE 17 -1 (2350 3950)(2350 4050);
WIRE 17 -1 (2350 4050)(2350 4150);
WIRE 17 -1 (2350 4150)(2350 4250);
WIRE 17 -1 (2350 4250)(2350 4350);
WIRE 17 -1 (2350 4350)(2350 4450);
WIRE 17 -1 (2350 4450)(2350 4550);
WIRE 17 -1 (2350 4550)(2350 4650);
WIRE 17 -1 (2350 4650)(2350 4750);
WIRE 17 -1 (3150 4875)(2350 4875);
FORCEPROP 2 LAST SIG_NAME M_K_DQS_DP<17:0>
J 0
(2600 4885);
DISPLAY 0.617021 (2600 4885);
PAINT ORANGE (2600 4885);
WIRE 17 -1 (2350 4750)(2350 4850);
WIRE 17 -1 (2350 4850)(2350 4875);
WIRE 17 -1 (-50 1350)(-50 1400);
WIRE 17 -1 (-50 1400)(-50 1450);
WIRE 17 -1 (-50 1450)(-50 1500);
WIRE 17 -1 (-50 1500)(-50 1550);
WIRE 17 -1 (-50 1550)(-50 1600);
WIRE 17 -1 (-50 1600)(-50 1650);
WIRE 17 -1 (-50 1650)(-50 1700);
WIRE 17 -1 (-50 1700)(-50 1750);
WIRE 17 -1 (-50 1750)(-50 1800);
WIRE 17 -1 (-50 1800)(-50 1850);
WIRE 17 -1 (-50 1850)(-50 1900);
WIRE 17 -1 (-50 1900)(-50 1950);
WIRE 17 -1 (-50 1950)(-50 2000);
WIRE 17 -1 (-50 2000)(-50 2050);
WIRE 17 -1 (-50 2050)(-50 2100);
WIRE 17 -1 (-50 2100)(-50 2150);
WIRE 17 -1 (-50 2150)(-50 2200);
WIRE 17 -1 (-50 2200)(-50 2250);
WIRE 17 -1 (-50 2250)(-50 2300);
WIRE 17 -1 (-50 2300)(-50 2350);
WIRE 17 -1 (-50 2350)(-50 2400);
WIRE 17 -1 (-50 2400)(-50 2450);
WIRE 17 -1 (-50 2450)(-50 2500);
WIRE 17 -1 (-50 2500)(-50 2550);
WIRE 17 -1 (-50 2550)(-50 2600);
WIRE 17 -1 (-50 2600)(-50 2650);
WIRE 17 -1 (-50 2650)(-50 2700);
WIRE 17 -1 (-50 2700)(-50 2750);
WIRE 17 -1 (-50 2750)(-50 2800);
WIRE 17 -1 (-50 2800)(-50 2850);
WIRE 17 -1 (-50 2850)(-50 2900);
WIRE 17 -1 (-50 2900)(-50 2950);
WIRE 17 -1 (-50 2950)(-50 3000);
WIRE 17 -1 (-50 3000)(-50 3050);
WIRE 17 -1 (-50 3050)(-50 3100);
WIRE 17 -1 (-50 3100)(-50 3150);
WIRE 17 -1 (-50 3150)(-50 3200);
WIRE 17 -1 (-50 3200)(-50 3250);
WIRE 17 -1 (-50 3250)(-50 3300);
WIRE 17 -1 (-50 3300)(-50 3350);
WIRE 17 -1 (-50 3350)(-50 3400);
WIRE 17 -1 (-50 3400)(-50 3450);
WIRE 17 -1 (-50 3450)(-50 3500);
WIRE 17 -1 (-50 3500)(-50 3550);
WIRE 17 -1 (-50 3550)(-50 3600);
WIRE 17 -1 (-50 3600)(-50 3650);
WIRE 17 -1 (-50 3650)(-50 3700);
WIRE 17 -1 (-50 3700)(-50 3750);
WIRE 17 -1 (-50 3750)(-50 3800);
WIRE 17 -1 (-50 3800)(-50 3850);
WIRE 17 -1 (-50 3850)(-50 3900);
WIRE 17 -1 (-50 3900)(-50 3950);
WIRE 17 -1 (-50 3950)(-50 4000);
WIRE 17 -1 (-50 4000)(-50 4050);
WIRE 17 -1 (-50 4050)(-50 4100);
WIRE 17 -1 (-50 4100)(-50 4150);
WIRE 17 -1 (-50 4150)(-50 4200);
WIRE 17 -1 (-50 4200)(-50 4250);
WIRE 17 -1 (-50 4250)(-50 4300);
WIRE 17 -1 (-50 4300)(-50 4350);
WIRE 17 -1 (-50 4350)(-50 4400);
WIRE 17 -1 (450 4525)(-50 4525);
FORCEPROP 2 LAST SIG_NAME M_K_DQ<63:0>
J 0
(40 4535);
DISPLAY 0.617021 (40 4535);
PAINT ORANGE (40 4535);
WIRE 17 -1 (-50 4500)(-50 4525);
WIRE 17 -1 (-50 4400)(-50 4450);
WIRE 17 -1 (-50 4450)(-50 4500);
WIRE 17 -1 (-1650 3650)(-1650 3700);
WIRE 17 -1 (-1650 3700)(-1650 3750);
WIRE 17 -1 (-1650 3750)(-1650 3800);
WIRE 17 -1 (-1650 3800)(-1650 3850);
WIRE 17 -1 (-1650 3850)(-1650 3900);
WIRE 17 -1 (-1650 3900)(-1650 3950);
WIRE 17 -1 (-1650 3950)(-1650 4000);
WIRE 17 -1 (-1650 4000)(-1650 4050);
WIRE 17 -1 (-2200 4525)(-1650 4525);
FORCEPROP 2 LAST SIG_NAME M_K_MA<17:0>
J 0
(-2175 4535);
DISPLAY 0.617021 (-2175 4535);
PAINT ORANGE (-2175 4535);
WIRE 17 -1 (-1650 4050)(-1650 4100);
WIRE 17 -1 (-1650 4100)(-1650 4150);
WIRE 17 -1 (-1650 4500)(-1650 4525);
WIRE 17 -1 (-1650 4450)(-1650 4500);
WIRE 17 -1 (-1650 4150)(-1650 4200);
WIRE 17 -1 (-1650 4200)(-1650 4250);
WIRE 17 -1 (-1650 4400)(-1650 4450);
WIRE 17 -1 (-1650 4350)(-1650 4400);
WIRE 17 -1 (-1650 4250)(-1650 4300);
WIRE 17 -1 (-1650 4300)(-1650 4350);
WIRE 17 -1 (-2000 3375)(-2600 3375);
FORCEPROP 2 LAST SIG_NAME M_K_CLK_DP<3:0>
J 0
(-2550 3385);
DISPLAY 0.617021 (-2550 3385);
PAINT ORANGE (-2550 3385);
WIRE 17 -1 (-2000 3375)(-2000 3300);
WIRE 17 -1 (-2000 3300)(-2000 3200);
WIRE 17 -1 (-1650 3475)(-2200 3475);
FORCEPROP 2 LAST SIG_NAME M_K_BG<1:0>
J 0
(-2175 3485);
DISPLAY 0.617021 (-2175 3485);
PAINT ORANGE (-2175 3485);
WIRE 17 -1 (-1650 3475)(-1650 3450);
WIRE 17 -1 (-1650 3400)(-1650 3450);
WIRE 17 -1 (-1650 3575)(-2200 3575);
FORCEPROP 2 LAST SIG_NAME M_K_BA<1:0>
J 0
(-2175 3585);
DISPLAY 0.617021 (-2175 3585);
PAINT ORANGE (-2175 3585);
WIRE 17 -1 (-1650 3575)(-1650 3550);
WIRE 17 -1 (-1650 3500)(-1650 3550);
WIRE 17 -1 (-1650 2100)(-1650 2150);
WIRE 17 -1 (-1650 2150)(-1650 2200);
WIRE 17 -1 (-1650 2200)(-1650 2250);
WIRE 17 -1 (-1650 2250)(-1650 2300);
WIRE 17 -1 (-1650 2300)(-1650 2350);
WIRE 17 -1 (-1650 2475)(-2200 2475);
FORCEPROP 2 LAST SIG_NAME M_K_ECC<7:0>
J 0
(-2175 2485);
DISPLAY 0.617021 (-2175 2485);
PAINT ORANGE (-2175 2485);
WIRE 17 -1 (-1650 2450)(-1650 2475);
WIRE 17 -1 (-1650 2350)(-1650 2400);
WIRE 17 -1 (-1650 2400)(-1650 2450);
WIRE 17 -1 (-1650 3025)(-2200 3025);
FORCEPROP 2 LAST SIG_NAME M_K_CS_N<7:0>
J 0
(-2175 3035);
DISPLAY 0.617021 (-2175 3035);
PAINT ORANGE (-2175 3035);
WIRE 17 -1 (-1650 3000)(-1650 3025);
WIRE 17 -1 (-1650 2950)(-1650 3000);
WIRE 17 -1 (-1650 2900)(-1650 2950);
WIRE 17 -1 (-1650 2850)(-1650 2900);
WIRE 17 -1 (-1650 2775)(-2200 2775);
FORCEPROP 2 LAST SIG_NAME M_K_CKE<3:0>
J 0
(-2175 2785);
DISPLAY 0.617021 (-2175 2785);
PAINT ORANGE (-2175 2785);
WIRE 17 -1 (-1650 2750)(-1650 2775);
WIRE 17 -1 (-1650 2700)(-1650 2750);
WIRE 17 -1 (-1650 2625)(-2200 2625);
FORCEPROP 2 LAST SIG_NAME M_K_ODT<3:0>
J 0
(-2175 2635);
DISPLAY 0.617021 (-2175 2635);
PAINT ORANGE (-2175 2635);
WIRE 17 -1 (-1650 2550)(-1650 2600);
WIRE 17 -1 (-1650 2600)(-1650 2625);
WIRE 17 -1 (-2150 3325)(-2600 3325);
FORCEPROP 2 LAST SIG_NAME M_K_CLK_DN<3:0>
J 0
(-2550 3335);
DISPLAY 0.617021 (-2550 3335);
PAINT ORANGE (-2550 3335);
WIRE 17 -1 (-2150 3250)(-2150 3325);
WIRE 17 -1 (-2150 3150)(-2150 3250);
WIRE 16 -1 (-150 4325)(-350 4325);
WIRE 16 -1 (2450 3775)(2050 3775);
WIRE 16 -1 (2450 3675)(2050 3675);
WIRE 16 -1 (2250 3825)(2050 3825);
WIRE 16 -1 (2450 4575)(2050 4575);
WIRE 16 -1 (-150 4375)(-350 4375);
WIRE 16 -1 (2250 3525)(2050 3525);
WIRE 16 -1 (-1350 1825)(-2375 1825);
FORCEPROP 2 LAST SIG_NAME M_K_ALERT_N
J 0
(-2325 1835);
DISPLAY 0.617021 (-2325 1835);
PAINT ORANGE (-2325 1835);
WIRE 16 -1 (-150 2875)(-350 2875);
WIRE 16 -1 (-150 2925)(-350 2925);
WIRE 16 -1 (-150 4475)(-350 4475);
WIRE 16 -1 (2450 3475)(2050 3475);
WIRE 16 -1 (2250 3425)(2050 3425);
WIRE 16 -1 (2450 3375)(2050 3375);
WIRE 16 -1 (2450 3275)(2050 3275);
WIRE 16 -1 (2250 3225)(2050 3225);
WIRE 16 -1 (2450 3175)(2050 3175);
WIRE 16 -1 (2250 3125)(2050 3125);
WIRE 16 -1 (-3100 1325)(-3000 1325);
WIRE 16 -1 (-3000 1325)(-3000 1225);
WIRE 16 -1 (-1350 1325)(-3000 1325);
FORCEPROP 2 LAST SIG_NAME M_K_VREF
J 0
(-2100 1335);
DISPLAY 0.617021 (-2100 1335);
PAINT ORANGE (-2100 1335);
WIRE 16 -1 (-2200 1225)(-1350 1225);
FORCEPROP 2 LAST SIG_NAME TP_CH_K_DIMM0_RFU_2
J 0
(-2150 1235);
DISPLAY 0.617021 (-2150 1235);
PAINT ORANGE (-2150 1235);
FORCEPROP 2 LASTPROP $XRERR UNIQUE?
J 0
(-2440 1225);
DISPLAY 0.638298 (-2440 1225);
PAINT MONO (-2440 1225);
DISPLAY INVISIBLE (-2440 1225);
WIRE 16 -1 (-2200 1125)(-1350 1125);
FORCEPROP 2 LAST SIG_NAME TP_CH_K_DIMM0_RFU_0
J 0
(-2150 1135);
DISPLAY 0.617021 (-2150 1135);
PAINT ORANGE (-2150 1135);
FORCEPROP 2 LASTPROP $XRERR UNIQUE?
J 0
(-2440 1125);
DISPLAY 0.638298 (-2440 1125);
PAINT MONO (-2440 1125);
DISPLAY INVISIBLE (-2440 1125);
WIRE 16 -1 (-2200 1175)(-1350 1175);
FORCEPROP 2 LAST SIG_NAME TP_CH_K_DIMM0_RFU_1
J 0
(-2150 1185);
DISPLAY 0.617021 (-2150 1185);
PAINT ORANGE (-2150 1185);
FORCEPROP 2 LASTPROP $XRERR UNIQUE?
J 0
(-2440 1175);
DISPLAY 0.638298 (-2440 1175);
PAINT MONO (-2440 1175);
DISPLAY INVISIBLE (-2440 1175);
WIRE 16 -1 (-1350 3225)(-2050 3225);
WIRE 16 -1 (-1350 3125)(-2050 3125);
WIRE 16 -1 (-2200 1025)(-1350 1025);
FORCEPROP 2 LAST SIG_NAME FM_ADR_COMPLETE_KLM_N
J 0
(-2150 1035);
DISPLAY 0.617021 (-2150 1035);
PAINT ORANGE (-2150 1035);
WIRE 16 -1 (-2150 1425)(-1350 1425);
FORCEPROP 2 LAST SIG_NAME SMB_DDR_KLM_VPP_SCL
J 0
(-2110 1435);
DISPLAY 0.617021 (-2110 1435);
PAINT ORANGE (-2110 1435);
WIRE 16 -1 (-1350 1475)(-2150 1475);
WIRE 16 -1 (-1350 1775)(-2350 1775);
FORCEPROP 2 LAST SIG_NAME M_K_ACT_N
J 0
(-2300 1785);
DISPLAY 0.617021 (-2300 1785);
PAINT ORANGE (-2300 1785);
WIRE 16 -1 (-150 1375)(-350 1375);
WIRE 16 -1 (-150 1425)(-350 1425);
WIRE 16 -1 (-150 1475)(-350 1475);
WIRE 16 -1 (-150 1525)(-350 1525);
WIRE 16 -1 (-150 1325)(-350 1325);
WIRE 16 -1 (-150 2025)(-350 2025);
WIRE 16 -1 (-150 1975)(-350 1975);
WIRE 16 -1 (-150 1925)(-350 1925);
WIRE 16 -1 (-150 1875)(-350 1875);
WIRE 16 -1 (-150 1825)(-350 1825);
WIRE 16 -1 (-150 1725)(-350 1725);
WIRE 16 -1 (-150 1675)(-350 1675);
WIRE 16 -1 (-150 1625)(-350 1625);
WIRE 16 -1 (-150 1575)(-350 1575);
WIRE 16 -1 (-150 1775)(-350 1775);
WIRE 16 -1 (-1700 2425)(-2200 2425);
FORCEPROP 2 LAST SIG_NAME M_K_PAR
J 0
(-2175 2435);
DISPLAY 0.617021 (-2175 2435);
PAINT ORANGE (-2175 2435);
WIRE 16 -1 (-1350 1975)(-1700 1975);
WIRE 16 -1 (-1700 1975)(-1700 2425);
WIRE 16 -1 (-1750 2375)(-2200 2375);
FORCEPROP 2 LAST SIG_NAME M_KLM_RST_N
J 0
(-2175 2385);
DISPLAY 0.617021 (-2175 2385);
PAINT ORANGE (-2175 2385);
WIRE 16 -1 (-1350 1925)(-1750 1925);
WIRE 16 -1 (-1750 1925)(-1750 2375);
WIRE 16 -1 (-1350 2975)(-1550 2975);
WIRE 16 -1 (-1350 2925)(-1550 2925);
WIRE 16 -1 (-1350 2875)(-1550 2875);
WIRE 16 -1 (-1350 2325)(-1550 2325);
WIRE 16 -1 (-1350 2275)(-1550 2275);
WIRE 16 -1 (-1350 2225)(-1550 2225);
WIRE 16 -1 (-1350 2175)(-1550 2175);
WIRE 16 -1 (-1350 2125)(-1550 2125);
WIRE 16 -1 (-1350 2075)(-1550 2075);
WIRE 16 -1 (-1350 2725)(-1550 2725);
WIRE 16 -1 (-1350 2425)(-1550 2425);
WIRE 16 -1 (-1350 2525)(-1550 2525);
WIRE 16 -1 (-1350 2575)(-1550 2575);
WIRE 16 -1 (-1350 2675)(-1550 2675);
WIRE 16 -1 (-1350 2825)(-1550 2825);
WIRE 16 -1 (-1350 2375)(-1550 2375);
WIRE 16 -1 (-1500 3025)(-1350 3025);
WIRE 16 -1 (-1500 3075)(-2200 3075);
FORCEPROP 2 LAST SIG_NAME M_K_C<2>
J 0
(-2175 3085);
DISPLAY 0.617021 (-2175 3085);
PAINT ORANGE (-2175 3085);
WIRE 16 -1 (-1500 3075)(-1500 3025);
WIRE 16 -1 (-1350 3525)(-1550 3525);
WIRE 16 -1 (-1350 3625)(-1550 3625);
WIRE 16 -1 (-1350 3675)(-1550 3675);
WIRE 16 -1 (-1350 3775)(-1550 3775);
WIRE 16 -1 (-1350 3825)(-1550 3825);
WIRE 16 -1 (-1350 3875)(-1550 3875);
WIRE 16 -1 (-1350 3925)(-1550 3925);
WIRE 16 -1 (-1350 3975)(-1550 3975);
WIRE 16 -1 (-1350 4025)(-1550 4025);
WIRE 16 -1 (-1350 4075)(-1550 4075);
WIRE 16 -1 (-1350 3475)(-1550 3475);
WIRE 16 -1 (-1350 3725)(-1550 3725);
WIRE 16 -1 (-1350 3425)(-1550 3425);
WIRE 16 -1 (-1350 3375)(-1550 3375);
WIRE 16 -1 (-1350 3275)(-1900 3275);
WIRE 16 -1 (-1350 3175)(-1900 3175);
WIRE 16 -1 (-150 2525)(-350 2525);
WIRE 16 -1 (-150 2475)(-350 2475);
WIRE 16 -1 (-150 2425)(-350 2425);
WIRE 16 -1 (-150 2375)(-350 2375);
WIRE 16 -1 (-150 2325)(-350 2325);
WIRE 16 -1 (-150 2275)(-350 2275);
WIRE 16 -1 (-150 2225)(-350 2225);
WIRE 16 -1 (-150 2125)(-350 2125);
WIRE 16 -1 (-150 2075)(-350 2075);
WIRE 16 -1 (-150 2175)(-350 2175);
WIRE 16 -1 (-150 2775)(-350 2775);
WIRE 16 -1 (-150 2725)(-350 2725);
WIRE 16 -1 (-150 3025)(-350 3025);
WIRE 16 -1 (-150 2975)(-350 2975);
WIRE 16 -1 (-150 2825)(-350 2825);
WIRE 16 -1 (-150 2575)(-350 2575);
WIRE 16 -1 (-150 2675)(-350 2675);
WIRE 16 -1 (-150 2625)(-350 2625);
WIRE 16 -1 (-150 3575)(-350 3575);
WIRE 16 -1 (-150 3525)(-350 3525);
WIRE 16 -1 (-150 3475)(-350 3475);
WIRE 16 -1 (-150 3425)(-350 3425);
WIRE 16 -1 (-150 3275)(-350 3275);
WIRE 16 -1 (-150 3175)(-350 3175);
WIRE 16 -1 (-150 3125)(-350 3125);
WIRE 16 -1 (-150 3225)(-350 3225);
WIRE 16 -1 (-150 3075)(-350 3075);
WIRE 16 -1 (-150 3325)(-350 3325);
WIRE 16 -1 (-150 3375)(-350 3375);
WIRE 16 -1 (-150 4075)(-350 4075);
WIRE 16 -1 (-150 3625)(-350 3625);
WIRE 16 -1 (-150 4025)(-350 4025);
WIRE 16 -1 (-150 3975)(-350 3975);
WIRE 16 -1 (-150 3925)(-350 3925);
WIRE 16 -1 (-150 3875)(-350 3875);
WIRE 16 -1 (-150 3825)(-350 3825);
WIRE 16 -1 (-150 3775)(-350 3775);
WIRE 16 -1 (-150 3725)(-350 3725);
WIRE 16 -1 (-150 3675)(-350 3675);
WIRE 16 -1 (-1350 4225)(-1550 4225);
WIRE 16 -1 (-1350 4475)(-1550 4475);
WIRE 16 -1 (-1350 4125)(-1550 4125);
WIRE 16 -1 (-1350 4175)(-1550 4175);
WIRE 16 -1 (-1350 4325)(-1550 4325);
WIRE 16 -1 (-1350 4375)(-1550 4375);
WIRE 16 -1 (-1350 4425)(-1550 4425);
WIRE 16 -1 (-1350 4275)(-1550 4275);
WIRE 16 -1 (-150 4275)(-350 4275);
WIRE 16 -1 (-150 4125)(-350 4125);
WIRE 16 -1 (-150 4175)(-350 4175);
WIRE 16 -1 (-150 4225)(-350 4225);
WIRE 16 -1 (-150 4425)(-350 4425);
WIRE 16 -1 (2250 3325)(2050 3325);
WIRE 16 -1 (2450 3075)(2050 3075);
WIRE 16 -1 (2450 3575)(2050 3575);
WIRE 16 -1 (2250 3625)(2050 3625);
WIRE 16 -1 (2250 3725)(2050 3725);
WIRE 16 -1 (2250 3925)(2050 3925);
WIRE 16 -1 (2250 4025)(2050 4025);
WIRE 16 -1 (2450 4075)(2050 4075);
WIRE 16 -1 (2450 3875)(2050 3875);
WIRE 16 -1 (2450 3975)(2050 3975);
WIRE 16 -1 (2250 4125)(2050 4125);
WIRE 16 -1 (2250 4225)(2050 4225);
WIRE 16 -1 (2250 4325)(2050 4325);
WIRE 16 -1 (2250 4425)(2050 4425);
WIRE 16 -1 (2250 4525)(2050 4525);
WIRE 16 -1 (2450 4175)(2050 4175);
WIRE 16 -1 (2450 4275)(2050 4275);
WIRE 16 -1 (2450 4375)(2050 4375);
WIRE 16 -1 (2450 4475)(2050 4475);
WIRE 16 -1 (2250 4625)(2050 4625);
WIRE 16 -1 (2250 4725)(2050 4725);
WIRE 16 -1 (2250 4825)(2050 4825);
WIRE 16 -1 (2450 4675)(2050 4675);
WIRE 16 -1 (2450 4775)(2050 4775);
WIRE 16 -1 (-1800 1875)(-1350 1875);
WIRE 16 -1 (-1800 2175)(-2525 2175);
FORCEPROP 2 LAST SIG_NAME FM_DIMM_EVENT_COD_N
J 0
(-2472 2192);
DISPLAY 0.617021 (-2472 2192);
PAINT ORANGE (-2472 2192);
WIRE 16 -1 (-1800 2175)(-1800 1875);
DOT 1 (4100 2825);
DOT 1 (750 2475);
DOT 1 (750 2125);
DOT 1 (-1500 1625);
DOT 1 (-1550 1675);
DOT 1 (750 1625);
DOT 1 (750 1775);
DOT 1 (750 2025);
DOT 1 (750 2075);
DOT 1 (-3000 1325);
DOT 1 (750 925);
DOT 1 (750 975);
DOT 1 (750 1025);
DOT 1 (750 1125);
DOT 1 (750 1075);
DOT 1 (750 1175);
DOT 1 (750 1225);
DOT 1 (750 1275);
DOT 1 (750 1325);
DOT 1 (750 1375);
DOT 1 (750 1425);
DOT 1 (750 1475);
DOT 1 (750 1525);
DOT 1 (750 1575);
DOT 1 (750 1675);
DOT 1 (750 1725);
DOT 1 (750 1825);
DOT 1 (750 1875);
DOT 1 (750 1925);
DOT 1 (750 1975);
DOT 1 (750 2275);
DOT 1 (750 2425);
DOT 1 (750 2525);
DOT 1 (750 2575);
DOT 1 (2700 875);
DOT 1 (2700 975);
DOT 1 (2700 1025);
DOT 1 (2700 925);
DOT 1 (2700 1125);
DOT 1 (2700 1075);
DOT 1 (2700 1225);
DOT 1 (2700 1175);
DOT 1 (2700 1275);
DOT 1 (2700 1375);
DOT 1 (2700 1325);
DOT 1 (2700 1425);
DOT 1 (2700 1475);
DOT 1 (2700 1525);
DOT 1 (2700 1575);
DOT 1 (2700 1625);
DOT 1 (2700 1675);
DOT 1 (2150 2575);
DOT 1 (2700 1725);
DOT 1 (2700 1775);
DOT 1 (2700 1925);
DOT 1 (2700 1875);
DOT 1 (2700 1825);
DOT 1 (2700 2025);
DOT 1 (2700 1975);
DOT 1 (2700 2175);
DOT 1 (2700 2125);
DOT 1 (2700 2075);
DOT 1 (2700 2225);
DOT 1 (2700 2275);
DOT 1 (2700 2325);
DOT 1 (2700 2425);
DOT 1 (2700 2375);
DOT 1 (2700 2525);
DOT 1 (2700 2475);
DOT 1 (2700 2575);
DOT 1 (2700 2675);
DOT 1 (2700 2625);
DOT 1 (2700 2775);
DOT 1 (2700 2825);
DOT 1 (2700 2725);
DOT 1 (2700 2875);
DOT 1 (2700 2925);
DOT 1 (2700 3025);
DOT 1 (2700 3075);
DOT 1 (2700 2975);
DOT 1 (2700 3125);
DOT 1 (4100 875);
DOT 1 (4100 975);
DOT 1 (4100 925);
DOT 1 (4100 1025);
DOT 1 (4100 1125);
DOT 1 (4100 1075);
DOT 1 (4100 1175);
DOT 1 (4100 1225);
DOT 1 (4100 1275);
DOT 1 (4100 1375);
DOT 1 (4100 1325);
DOT 1 (4100 1425);
DOT 1 (4100 1525);
DOT 1 (4100 1475);
DOT 1 (4100 1625);
DOT 1 (4100 1575);
DOT 1 (4100 1675);
DOT 1 (4100 1775);
DOT 1 (4100 1725);
DOT 1 (4100 1875);
DOT 1 (4100 1825);
DOT 1 (4100 1925);
DOT 1 (4100 1975);
DOT 1 (4100 2025);
DOT 1 (4100 2125);
DOT 1 (4100 2175);
DOT 1 (4100 2075);
DOT 1 (4100 2225);
DOT 1 (4100 2275);
DOT 1 (4100 2325);
DOT 1 (4100 2425);
DOT 1 (4100 2375);
DOT 1 (4100 2475);
DOT 1 (4100 2525);
DOT 1 (4100 2575);
DOT 1 (4100 2675);
DOT 1 (4100 2625);
DOT 1 (4100 2725);
DOT 1 (4100 2775);
DOT 1 (4100 2875);
DOT 1 (4100 2925);
DOT 1 (4100 3025);
DOT 1 (4100 3075);
DOT 1 (4100 2975);
DOT 1 (4100 3125);
FORCENOTE
PVDDQ (SINGLE SIDE) CAP: 10UF X1, 22UF X50
(-1700 4825) 0;
DISPLAY LEFT (-1700 4825);
DISPLAY 1.021277 (-1700 4825);
PAINT PURPLE (-1700 4825);
FORCENOTE
PVTT CAP: 100UF X2, 47UF X1
(-1700 4875) 0;
DISPLAY LEFT (-1700 4875);
DISPLAY 1.021277 (-1700 4875);
PAINT PURPLE (-1700 4875);
FORCENOTE
CAP BETWEEN DIMM
(-1700 5000) 0;
DISPLAY LEFT (-1700 5000);
DISPLAY 1.276596 (-1700 5000);
PAINT PURPLE (-1700 5000);
FORCENOTE
PVDDQ (DOUBLE SIDE) CAP: 100UF X8, 47UF X41
(-1700 4775) 0;
DISPLAY LEFT (-1700 4775);
DISPLAY 1.021277 (-1700 4775);
PAINT PURPLE (-1700 4775);
FORCENOTE
PVPP CAP: 10UF X12
(-1700 4925) 0;
DISPLAY LEFT (-1700 4925);
DISPLAY 1.021277 (-1700 4925);
PAINT PURPLE (-1700 4925);
FORCENOTE
PLACE CAP NEAR DIMM CONNECTOR
(-3688 777) 0;
DISPLAY LEFT (-3688 777);
DISPLAY 1.595745 (-3688 777);
PAINT PURPLE (-3688 777);
FORCENOTE
SMBUS ADDR: 0XA2
(-1300 709) 0;
DISPLAY LEFT (-1300 709);
DISPLAY 1.957447 (-1300 709);
PAINT PURPLE (-1300 709);
QUIT
